FILE_TYPE = MACRO_DRAWING;
SET COLOR_WIRE YELLOW;
SET COLOR_PROP ORANGE;
SET COLOR_DOT WHITE;
SET COLOR_ARC YELLOW;
SET COLOR_BODY GREEN;
SET COLOR_NOTE PURPLE;
SET PROP_DISPLAY VALUE;
SET PAGE_NUMBER P186;
FORCEADD OFFPAGE..1
(-8150 1600);
FORCEPROP 2 LAST $XR5 216 
J 0
(-9002 1600);
DISPLAY 0.638298 (-9002 1600);
PAINT MONO (-9002 1600);
FORCEPROP 2 LAST $XR2 212 
J 0
(-8642 1600);
DISPLAY 0.638298 (-8642 1600);
PAINT MONO (-8642 1600);
FORCEPROP 2 LAST $XR1 211 
J 0
(-8522 1600);
DISPLAY 0.638298 (-8522 1600);
PAINT MONO (-8522 1600);
FORCEPROP 2 LAST $XR0 210 
J 0
(-8402 1600);
DISPLAY 0.638298 (-8402 1600);
PAINT MONO (-8402 1600);
FORCEPROP 2 LAST $XR3 213 
J 0
(-8762 1600);
DISPLAY 0.638298 (-8762 1600);
PAINT MONO (-8762 1600);
FORCEPROP 2 LAST $XR4 215 
J 0
(-8882 1600);
DISPLAY 0.638298 (-8882 1600);
PAINT MONO (-8882 1600);
FORCEPROP 2 LAST CDS_LIB standard
J 0
(-8150 1600);
DISPLAY INVISIBLE (-8150 1600);
FORCEPROP 1 LAST OFFPAGE TRUE
J 0
(-7825 1475);
DISPLAY 0.872340 (-7825 1475);
PAINT GREEN (-7825 1475);
DISPLAY INVISIBLE (-7825 1475);
FORCEPROP 1 LAST COMMENT_BODY TRUE
J 0
(-8025 1500);
DISPLAY 0.872340 (-8025 1500);
PAINT GREEN (-8025 1500);
DISPLAY INVISIBLE (-8025 1500);
FORCEPROP 2 LAST PATH I1
J 0
(-8400 1650);
DISPLAY 0.680851 (-8400 1650);
DISPLAY INVISIBLE (-8400 1650);
FORCEADD UNIVERSAL_GND..1
(-7575 1850);
FORCEPROP 3 LASTPIN (-7575 1900) SIG_NAME GND\g
J 0
(-7565 1910);
DISPLAY 0.659574 (-7565 1910);
PAINT MONO (-7565 1910);
DISPLAY INVISIBLE (-7565 1910);
FORCEPROP 2 LAST CDS_LIB pure_quanta_power
J 0
(-7575 1850);
DISPLAY INVISIBLE (-7575 1850);
FORCEPROP 1 LAST HDL_POWER GND
J 1
(-7550 1775);
DISPLAY 0.872340 (-7550 1775);
PAINT GREEN (-7550 1775);
DISPLAY INVISIBLE (-7550 1775);
FORCEPROP 1 LAST PATH I10
J 0
(-7500 1850);
DISPLAY 0.872340 (-7500 1850);
PAINT AQUA (-7500 1850);
DISPLAY INVISIBLE (-7500 1850);
FORCEADD Q_RES..2
(-7575 2600);
FORCEPROP 1 LAST LOCATION PR186
J 0
(-7530 2725);
DISPLAY 0.489362 (-7530 2725);
PAINT SKYBLUE (-7530 2725);
FORCEPROP 0 LAST $SEC 1
J 0
(-7525 2775);
DISPLAY 0.680851 (-7525 2775);
PAINT MONO (-7525 2775);
DISPLAY INVISIBLE (-7525 2775);
FORCEPROP 0 LAST CDS_SEC 1
J 0
(-7525 2775);
DISPLAY 1.021277 (-7525 2775);
DISPLAY INVISIBLE (-7525 2775);
FORCEPROP 1 LASTPIN (-7575 2700) $PN 1
J 0
(-7570 2662);
DISPLAY 0.489362 (-7570 2662);
PAINT MONO (-7570 2662);
FORCEPROP 1 LASTPIN (-7575 2500) $PN 2
J 0
(-7570 2510);
DISPLAY 0.489362 (-7570 2510);
PAINT MONO (-7570 2510);
FORCEPROP 1 LAST VALUE 2.2
J 0
(-7525 2675);
DISPLAY 0.489362 (-7525 2675);
PAINT SKYBLUE (-7525 2675);
FORCEPROP 1 LAST PACK_TYPE 0402LF
J 0
(-7525 2425);
DISPLAY 0.489362 (-7525 2425);
PAINT SKYBLUE (-7525 2425);
FORCEPROP 1 LAST TOLERANCE 1%
J 0
(-7525 2625);
DISPLAY 0.489362 (-7525 2625);
PAINT SKYBLUE (-7525 2625);
FORCEPROP 1 LAST MATERIAL CHIP
J 0
(-7525 2525);
DISPLAY 0.489362 (-7525 2525);
PAINT SKYBLUE (-7525 2525);
FORCEPROP 1 LAST WATTAGE 1/16W
J 0
(-7525 2575);
DISPLAY 0.489362 (-7525 2575);
PAINT SKYBLUE (-7525 2575);
FORCEPROP 2 LAST CDS_LIB pure_quanta
J 0
(-7575 2600);
DISPLAY INVISIBLE (-7575 2600);
FORCEPROP 1 LAST PATH I11
J 0
(-7525 2775);
DISPLAY 0.978723 (-7525 2775);
PAINT WHITE (-7525 2775);
DISPLAY INVISIBLE (-7525 2775);
FORCEPROP 1 LAST PART_NUMBER CS-2202FB01
J 0
(-7525 2475);
DISPLAY 0.489362 (-7525 2475);
PAINT SKYBLUE (-7525 2475);
DISPLAY INVISIBLE (-7525 2475);
FORCEADD UNIVERSAL_GND..1
(-7225 2350);
FORCEPROP 3 LASTPIN (-7225 2400) SIG_NAME GND\g
J 0
(-7215 2410);
DISPLAY 0.659574 (-7215 2410);
PAINT MONO (-7215 2410);
DISPLAY INVISIBLE (-7215 2410);
FORCEPROP 2 LAST CDS_LIB pure_quanta_power
J 0
(-7225 2350);
DISPLAY INVISIBLE (-7225 2350);
FORCEPROP 1 LAST HDL_POWER GND
J 1
(-7200 2275);
DISPLAY 0.872340 (-7200 2275);
PAINT GREEN (-7200 2275);
DISPLAY INVISIBLE (-7200 2275);
FORCEPROP 1 LAST PATH I12
J 0
(-7150 2350);
DISPLAY 0.872340 (-7150 2350);
PAINT AQUA (-7150 2350);
DISPLAY INVISIBLE (-7150 2350);
FORCEADD Q_CAP..1
(-7225 2625);
FORCEPROP 1 LAST LOCATION PC259_C0P1_2
J 0
(-7175 2725);
DISPLAY 0.489362 (-7175 2725);
PAINT SKYBLUE (-7175 2725);
FORCEPROP 0 LAST $SEC 1
J 0
(-7175 2775);
DISPLAY 0.680851 (-7175 2775);
PAINT MONO (-7175 2775);
DISPLAY INVISIBLE (-7175 2775);
FORCEPROP 0 LAST CDS_SEC 1
J 0
(-7175 2775);
DISPLAY 1.021277 (-7175 2775);
DISPLAY INVISIBLE (-7175 2775);
FORCEPROP 1 LASTPIN (-7225 2725) $PN 1
J 0
(-7215 2705);
DISPLAY 0.489362 (-7215 2705);
PAINT MONO (-7215 2705);
FORCEPROP 1 LASTPIN (-7225 2525) $PN 2
J 0
(-7215 2505);
DISPLAY 0.489362 (-7215 2505);
PAINT MONO (-7215 2505);
FORCEPROP 1 LAST MATERIAL X6S
J 0
(-7175 2525);
DISPLAY 0.489362 (-7175 2525);
PAINT SKYBLUE (-7175 2525);
FORCEPROP 1 LAST VALUE 2.2UF
J 0
(-7175 2675);
DISPLAY 0.489362 (-7175 2675);
PAINT SKYBLUE (-7175 2675);
FORCEPROP 1 LAST VOLTAGE 10V
J 0
(-7175 2625);
DISPLAY 0.489362 (-7175 2625);
PAINT SKYBLUE (-7175 2625);
FORCEPROP 1 LAST PACK_TYPE C0402
J 0
(-7175 2425);
DISPLAY 0.489362 (-7175 2425);
PAINT SKYBLUE (-7175 2425);
FORCEPROP 1 LAST TOLERANCE 10%
J 0
(-7175 2575);
DISPLAY 0.489362 (-7175 2575);
PAINT SKYBLUE (-7175 2575);
FORCEPROP 2 LAST CDS_LIB pure_quanta
J 0
(-7225 2625);
DISPLAY INVISIBLE (-7225 2625);
FORCEPROP 1 LAST PATH I13
J 0
(-7175 2775);
DISPLAY 0.978723 (-7175 2775);
PAINT WHITE (-7175 2775);
DISPLAY INVISIBLE (-7175 2775);
FORCEPROP 1 LAST PART_NUMBER CH5222KEB01
J 0
(-7175 2475);
DISPLAY 0.489362 (-7175 2475);
PAINT SKYBLUE (-7175 2475);
DISPLAY INVISIBLE (-7175 2475);
FORCEADD VCC_CORE..1
(-7575 3000);
FORCEPROP 3 LASTPIN (-7575 2950) SIG_NAME PVDDCR_CPU0_P1_PVCC\g
J 0
(-7565 2960);
DISPLAY 0.659574 (-7565 2960);
PAINT MONO (-7565 2960);
DISPLAY INVISIBLE (-7565 2960);
FORCEPROP 1 LAST HDL_POWER PVDDCR_CPU0_P1_PVCC
J 1
(-7575 3050);
DISPLAY 0.489362 (-7575 3050);
PAINT GREEN (-7575 3050);
FORCEPROP 2 LAST CDS_LIB pure_quanta_power
J 0
(-7575 3000);
DISPLAY INVISIBLE (-7575 3000);
FORCEPROP 1 LAST PATH I14
J 0
(-7525 3025);
DISPLAY 0.872340 (-7525 3025);
PAINT AQUA (-7525 3025);
DISPLAY INVISIBLE (-7525 3025);
FORCEADD UNIVERSAL_GND..1
(-7950 3900);
FORCEPROP 3 LASTPIN (-7950 3950) SIG_NAME GND\g
J 0
(-7940 3960);
DISPLAY 0.659574 (-7940 3960);
PAINT MONO (-7940 3960);
DISPLAY INVISIBLE (-7940 3960);
FORCEPROP 2 LAST CDS_LIB pure_quanta_power
J 0
(-7950 3900);
DISPLAY INVISIBLE (-7950 3900);
FORCEPROP 1 LAST HDL_POWER GND
J 1
(-7925 3825);
DISPLAY 0.872340 (-7925 3825);
PAINT GREEN (-7925 3825);
DISPLAY INVISIBLE (-7925 3825);
FORCEPROP 1 LAST PATH I15
J 0
(-7875 3900);
DISPLAY 0.872340 (-7875 3900);
PAINT AQUA (-7875 3900);
DISPLAY INVISIBLE (-7875 3900);
FORCEADD Q_CAP..1
(-7950 4175);
FORCEPROP 1 LAST LOCATION PC254_1
J 0
(-7900 4275);
DISPLAY 0.489362 (-7900 4275);
PAINT SKYBLUE (-7900 4275);
FORCEPROP 0 LAST $SEC 1
J 0
(-7900 4300);
DISPLAY 0.680851 (-7900 4300);
PAINT MONO (-7900 4300);
DISPLAY INVISIBLE (-7900 4300);
FORCEPROP 0 LAST CDS_SEC 1
J 0
(-7900 4300);
DISPLAY 1.021277 (-7900 4300);
DISPLAY INVISIBLE (-7900 4300);
FORCEPROP 1 LASTPIN (-7950 4275) $PN 1
J 0
(-7940 4255);
DISPLAY 0.489362 (-7940 4255);
PAINT MONO (-7940 4255);
FORCEPROP 1 LASTPIN (-7950 4075) $PN 2
J 0
(-7940 4055);
DISPLAY 0.489362 (-7940 4055);
PAINT MONO (-7940 4055);
FORCEPROP 1 LAST MATERIAL X7R
J 0
(-7900 4075);
DISPLAY 0.489362 (-7900 4075);
PAINT SKYBLUE (-7900 4075);
FORCEPROP 1 LAST TOLERANCE 10%
J 0
(-7900 4125);
DISPLAY 0.489362 (-7900 4125);
PAINT SKYBLUE (-7900 4125);
FORCEPROP 1 LAST VALUE 0.1UF
J 0
(-7900 4225);
DISPLAY 0.489362 (-7900 4225);
PAINT SKYBLUE (-7900 4225);
FORCEPROP 1 LAST VOLTAGE 25V
J 0
(-7900 4175);
DISPLAY 0.489362 (-7900 4175);
PAINT SKYBLUE (-7900 4175);
FORCEPROP 1 LAST PACK_TYPE 0402
J 0
(-7900 3975);
DISPLAY 0.489362 (-7900 3975);
PAINT SKYBLUE (-7900 3975);
FORCEPROP 2 LAST CDS_LIB pure_quanta
J 0
(-7950 4175);
DISPLAY INVISIBLE (-7950 4175);
FORCEPROP 1 LAST PATH I16
J 0
(-7900 4325);
DISPLAY 0.978723 (-7900 4325);
PAINT WHITE (-7900 4325);
DISPLAY INVISIBLE (-7900 4325);
FORCEPROP 1 LAST PART_NUMBER CH4104K1B00
J 0
(-7900 4025);
DISPLAY 0.489362 (-7900 4025);
PAINT SKYBLUE (-7900 4025);
DISPLAY INVISIBLE (-7900 4025);
FORCEADD UNIVERSAL_GND..1
(-7625 3975);
FORCEPROP 3 LASTPIN (-7625 4025) SIG_NAME GND\g
J 0
(-7615 4035);
DISPLAY 0.659574 (-7615 4035);
PAINT MONO (-7615 4035);
DISPLAY INVISIBLE (-7615 4035);
FORCEPROP 2 LAST CDS_LIB pure_quanta_power
J 0
(-7625 3975);
DISPLAY INVISIBLE (-7625 3975);
FORCEPROP 1 LAST HDL_POWER GND
J 1
(-7600 3900);
DISPLAY 0.872340 (-7600 3900);
PAINT GREEN (-7600 3900);
DISPLAY INVISIBLE (-7600 3900);
FORCEPROP 1 LAST PATH I17
J 0
(-7550 3975);
DISPLAY 0.872340 (-7550 3975);
PAINT AQUA (-7550 3975);
DISPLAY INVISIBLE (-7550 3975);
FORCEADD OFFPAGE..1
(-7225 3850);
FORCEPROP 2 LAST $XR0 210 
J 0
(-7477 3850);
DISPLAY 0.638298 (-7477 3850);
PAINT MONO (-7477 3850);
FORCEPROP 2 LAST CDS_LIB standard
J 2
(-7225 3850);
DISPLAY INVISIBLE (-7225 3850);
FORCEPROP 1 LAST OFFPAGE TRUE
J 0
(-6900 3725);
DISPLAY 0.872340 (-6900 3725);
PAINT GREEN (-6900 3725);
DISPLAY INVISIBLE (-6900 3725);
FORCEPROP 1 LAST COMMENT_BODY TRUE
J 0
(-7100 3750);
DISPLAY 0.872340 (-7100 3750);
PAINT GREEN (-7100 3750);
DISPLAY INVISIBLE (-7100 3750);
FORCEPROP 2 LAST PATH I18
J 0
(-7500 3900);
DISPLAY 0.680851 (-7500 3900);
DISPLAY INVISIBLE (-7500 3900);
FORCEADD OFFPAGE..2
R 2
(-7250 3950);
FORCEPROP 2 LAST $XR3 210 
J 0
(-7745 3914);
DISPLAY 0.638298 (-7745 3914);
PAINT MONO (-7745 3914);
FORCEPROP 2 LAST $XR2 213 
J 0
(-7625 3914);
DISPLAY 0.638298 (-7625 3914);
PAINT MONO (-7625 3914);
FORCEPROP 2 LAST $XR1 212 
J 0
(-7505 3914);
DISPLAY 0.638298 (-7505 3914);
PAINT MONO (-7505 3914);
FORCEPROP 2 LAST $XR0 211 
J 0
(-7505 3950);
DISPLAY 0.638298 (-7505 3950);
PAINT MONO (-7505 3950);
FORCEPROP 2 LAST CDS_LIB standard
J 0
(-7250 3950);
DISPLAY INVISIBLE (-7250 3950);
FORCEPROP 1 LAST OFFPAGE TRUE
J 2
(-7575 3825);
DISPLAY 0.872340 (-7575 3825);
PAINT GREEN (-7575 3825);
DISPLAY INVISIBLE (-7575 3825);
FORCEPROP 1 LAST COMMENT_BODY TRUE
J 2
(-7205 3855);
DISPLAY 0.872340 (-7205 3855);
PAINT GREEN (-7205 3855);
DISPLAY INVISIBLE (-7205 3855);
FORCEPROP 2 LAST PATH I19
J 0
(-7525 4000);
DISPLAY 0.680851 (-7525 4000);
DISPLAY INVISIBLE (-7525 4000);
FORCEADD OFFPAGE..1
(-8175 4350);
FORCEPROP 2 LAST $XR5 216 
J 0
(-9057 4350);
DISPLAY 0.638298 (-9057 4350);
PAINT MONO (-9057 4350);
FORCEPROP 2 LAST $XR4 215 
J 0
(-8937 4350);
DISPLAY 0.638298 (-8937 4350);
PAINT MONO (-8937 4350);
FORCEPROP 2 LAST $XR3 213 
J 0
(-8817 4350);
DISPLAY 0.638298 (-8817 4350);
PAINT MONO (-8817 4350);
FORCEPROP 2 LAST $XR2 212 
J 0
(-8697 4350);
DISPLAY 0.638298 (-8697 4350);
PAINT MONO (-8697 4350);
FORCEPROP 2 LAST $XR1 211 
J 0
(-8577 4350);
DISPLAY 0.638298 (-8577 4350);
PAINT MONO (-8577 4350);
FORCEPROP 2 LAST $XR0 210 
J 0
(-8457 4350);
DISPLAY 0.638298 (-8457 4350);
PAINT MONO (-8457 4350);
FORCEPROP 2 LAST CDS_LIB standard
J 0
(-8175 4350);
DISPLAY INVISIBLE (-8175 4350);
FORCEPROP 1 LAST OFFPAGE TRUE
J 0
(-7850 4225);
DISPLAY 0.872340 (-7850 4225);
PAINT GREEN (-7850 4225);
DISPLAY INVISIBLE (-7850 4225);
FORCEPROP 1 LAST COMMENT_BODY TRUE
J 0
(-8050 4250);
DISPLAY 0.872340 (-8050 4250);
PAINT GREEN (-8050 4250);
DISPLAY INVISIBLE (-8050 4250);
FORCEPROP 2 LAST PATH I2
J 0
(-8425 4400);
DISPLAY 0.680851 (-8425 4400);
DISPLAY INVISIBLE (-8425 4400);
FORCEADD UNIVERSAL_GND..1
(-5550 975);
FORCEPROP 3 LASTPIN (-5550 1025) SIG_NAME GND\g
J 0
(-5540 1035);
DISPLAY 0.659574 (-5540 1035);
PAINT MONO (-5540 1035);
DISPLAY INVISIBLE (-5540 1035);
FORCEPROP 2 LAST CDS_LIB pure_quanta_power
J 0
(-5550 975);
DISPLAY INVISIBLE (-5550 975);
FORCEPROP 1 LAST HDL_POWER GND
J 1
(-5525 900);
DISPLAY 0.872340 (-5525 900);
PAINT GREEN (-5525 900);
DISPLAY INVISIBLE (-5525 900);
FORCEPROP 1 LAST PATH I20
J 0
(-5475 975);
DISPLAY 0.872340 (-5475 975);
PAINT AQUA (-5475 975);
DISPLAY INVISIBLE (-5475 975);
FORCEADD UNIVERSAL_GND..1
(-4650 775);
FORCEPROP 3 LASTPIN (-4650 825) SIG_NAME GND\g
J 0
(-4640 835);
DISPLAY 0.659574 (-4640 835);
PAINT MONO (-4640 835);
DISPLAY INVISIBLE (-4640 835);
FORCEPROP 2 LAST CDS_LIB pure_quanta_power
J 0
(-4650 775);
DISPLAY INVISIBLE (-4650 775);
FORCEPROP 1 LAST HDL_POWER GND
J 1
(-4625 700);
DISPLAY 0.872340 (-4625 700);
PAINT GREEN (-4625 700);
DISPLAY INVISIBLE (-4625 700);
FORCEPROP 1 LAST PATH I21
J 0
(-4575 775);
DISPLAY 0.872340 (-4575 775);
PAINT AQUA (-4575 775);
DISPLAY INVISIBLE (-4575 775);
FORCEADD Q_RES..2
(-4650 1000);
FORCEPROP 1 LAST LOCATION PR486
J 0
(-4605 1125);
DISPLAY 0.489362 (-4605 1125);
PAINT SKYBLUE (-4605 1125);
FORCEPROP 0 LAST $SEC 1
J 0
(-4600 1175);
DISPLAY 0.680851 (-4600 1175);
PAINT MONO (-4600 1175);
DISPLAY INVISIBLE (-4600 1175);
FORCEPROP 0 LAST CDS_SEC 1
J 0
(-4600 1175);
DISPLAY 1.021277 (-4600 1175);
DISPLAY INVISIBLE (-4600 1175);
FORCEPROP 1 LASTPIN (-4650 1100) $PN 1
J 0
(-4645 1062);
DISPLAY 0.489362 (-4645 1062);
PAINT MONO (-4645 1062);
FORCEPROP 1 LASTPIN (-4650 900) $PN 2
J 0
(-4645 910);
DISPLAY 0.489362 (-4645 910);
PAINT MONO (-4645 910);
FORCEPROP 1 LAST WATTAGE 1/8W
J 0
(-4610 975);
DISPLAY 0.489362 (-4610 975);
PAINT SKYBLUE (-4610 975);
FORCEPROP 1 LAST MATERIAL EMPTY
J 0
(-4610 925);
DISPLAY 0.489362 (-4610 925);
PAINT RED (-4610 925);
FORCEPROP 1 LAST TOLERANCE 1%
J 0
(-4605 1025);
DISPLAY 0.489362 (-4605 1025);
PAINT SKYBLUE (-4605 1025);
FORCEPROP 1 LAST VALUE 1.5
J 0
(-4605 1075);
DISPLAY 0.489362 (-4605 1075);
PAINT SKYBLUE (-4605 1075);
FORCEPROP 1 LAST PACK_TYPE 0402LF
J 0
(-4610 825);
DISPLAY 0.489362 (-4610 825);
PAINT SKYBLUE (-4610 825);
FORCEPROP 2 LAST CDS_LIB pure_quanta
J 0
(-4650 1000);
DISPLAY INVISIBLE (-4650 1000);
FORCEPROP 1 LAST PATH I22
J 0
(-4600 1175);
DISPLAY 0.978723 (-4600 1175);
PAINT WHITE (-4600 1175);
DISPLAY INVISIBLE (-4600 1175);
FORCEPROP 1 LAST PART_NUMBER CS-1504FB00
J 0
(-4610 875);
DISPLAY 0.489362 (-4610 875);
PAINT SKYBLUE (-4610 875);
DISPLAY INVISIBLE (-4610 875);
FORCEADD Q_RES..1
(-4250 625);
FORCEPROP 1 LAST LOCATION PR192
J 0
(-4275 700);
DISPLAY 0.489362 (-4275 700);
PAINT SKYBLUE (-4275 700);
FORCEPROP 0 LAST $SEC 1
J 0
(-4250 700);
DISPLAY 0.680851 (-4250 700);
PAINT MONO (-4250 700);
DISPLAY INVISIBLE (-4250 700);
FORCEPROP 0 LAST CDS_SEC 1
J 0
(-4250 700);
DISPLAY 1.021277 (-4250 700);
DISPLAY INVISIBLE (-4250 700);
FORCEPROP 1 LASTPIN (-4350 625) $PN 1
J 0
(-4338 637);
DISPLAY 0.489362 (-4338 637);
PAINT MONO (-4338 637);
FORCEPROP 1 LASTPIN (-4150 625) $PN 2
J 0
(-4188 637);
DISPLAY 0.489362 (-4188 637);
PAINT MONO (-4188 637);
FORCEPROP 1 LAST PACK_TYPE 0402LF
J 0
(-4150 525);
DISPLAY 0.489362 (-4150 525);
PAINT SKYBLUE (-4150 525);
FORCEPROP 1 LAST VALUE 0
J 2
(-4375 650);
DISPLAY 0.489362 (-4375 650);
PAINT SKYBLUE (-4375 650);
FORCEPROP 1 LAST TOLERANCE 5%
J 0
(-4125 650);
DISPLAY 0.489362 (-4125 650);
PAINT SKYBLUE (-4125 650);
FORCEPROP 1 LAST MATERIAL CHIP
J 0
(-4500 525);
DISPLAY 0.489362 (-4500 525);
PAINT SKYBLUE (-4500 525);
FORCEPROP 1 LAST WATTAGE 1/16W
J 0
(-4150 575);
DISPLAY 0.489362 (-4150 575);
PAINT SKYBLUE (-4150 575);
FORCEPROP 2 LAST CDS_LIB pure_quanta
J 0
(-4250 625);
DISPLAY INVISIBLE (-4250 625);
FORCEPROP 1 LAST PATH I23
J 0
(-4300 775);
DISPLAY 0.978723 (-4300 775);
PAINT WHITE (-4300 775);
DISPLAY INVISIBLE (-4300 775);
FORCEPROP 1 LAST PART_NUMBER CS00002JB13
J 0
(-4500 575);
DISPLAY 0.489362 (-4500 575);
PAINT SKYBLUE (-4500 575);
DISPLAY INVISIBLE (-4500 575);
FORCEADD Q_CAP..1
(-4650 1500);
FORCEPROP 1 LAST LOCATION PC173
J 0
(-4600 1600);
DISPLAY 0.489362 (-4600 1600);
PAINT SKYBLUE (-4600 1600);
FORCEPROP 0 LAST $SEC 1
J 0
(-4600 1650);
DISPLAY 0.680851 (-4600 1650);
PAINT MONO (-4600 1650);
DISPLAY INVISIBLE (-4600 1650);
FORCEPROP 0 LAST CDS_SEC 1
J 0
(-4600 1650);
DISPLAY 1.021277 (-4600 1650);
DISPLAY INVISIBLE (-4600 1650);
FORCEPROP 1 LASTPIN (-4650 1600) $PN 1
J 0
(-4640 1580);
DISPLAY 0.489362 (-4640 1580);
PAINT MONO (-4640 1580);
FORCEPROP 1 LASTPIN (-4650 1400) $PN 2
J 0
(-4640 1380);
DISPLAY 0.489362 (-4640 1380);
PAINT MONO (-4640 1380);
FORCEPROP 1 LAST MATERIAL EMPTY
J 0
(-4600 1400);
DISPLAY 0.489362 (-4600 1400);
PAINT RED (-4600 1400);
FORCEPROP 1 LAST TOLERANCE 10%
J 0
(-4600 1450);
DISPLAY 0.489362 (-4600 1450);
PAINT SKYBLUE (-4600 1450);
FORCEPROP 1 LAST VALUE 560PF
J 0
(-4600 1550);
DISPLAY 0.489362 (-4600 1550);
PAINT SKYBLUE (-4600 1550);
FORCEPROP 1 LAST VOLTAGE 50V
J 0
(-4600 1500);
DISPLAY 0.489362 (-4600 1500);
PAINT SKYBLUE (-4600 1500);
FORCEPROP 1 LAST PACK_TYPE C0402
J 0
(-4600 1300);
DISPLAY 0.489362 (-4600 1300);
PAINT SKYBLUE (-4600 1300);
FORCEPROP 2 LAST CDS_LIB pure_quanta
J 0
(-4650 1500);
DISPLAY INVISIBLE (-4650 1500);
FORCEPROP 1 LAST PATH I24
J 0
(-4600 1650);
DISPLAY 0.978723 (-4600 1650);
PAINT WHITE (-4600 1650);
DISPLAY INVISIBLE (-4600 1650);
FORCEPROP 1 LAST PART_NUMBER CH1566K1B09
J 0
(-4600 1350);
DISPLAY 0.489362 (-4600 1350);
PAINT SKYBLUE (-4600 1350);
DISPLAY INVISIBLE (-4600 1350);
FORCEADD Q_CAP..1
(-5475 2575);
FORCEPROP 1 LAST LOCATION PC261_2
J 0
(-5425 2675);
DISPLAY 0.489362 (-5425 2675);
PAINT SKYBLUE (-5425 2675);
FORCEPROP 0 LAST $SEC 1
J 0
(-5425 2725);
DISPLAY 0.680851 (-5425 2725);
PAINT MONO (-5425 2725);
DISPLAY INVISIBLE (-5425 2725);
FORCEPROP 0 LAST CDS_SEC 1
J 0
(-5425 2725);
DISPLAY 1.021277 (-5425 2725);
DISPLAY INVISIBLE (-5425 2725);
FORCEPROP 1 LASTPIN (-5475 2675) $PN 1
J 0
(-5465 2655);
DISPLAY 0.489362 (-5465 2655);
PAINT MONO (-5465 2655);
FORCEPROP 1 LASTPIN (-5475 2475) $PN 2
J 0
(-5465 2455);
DISPLAY 0.489362 (-5465 2455);
PAINT MONO (-5465 2455);
FORCEPROP 1 LAST PACK_TYPE 0402
J 0
(-5425 2375);
DISPLAY 0.489362 (-5425 2375);
PAINT SKYBLUE (-5425 2375);
FORCEPROP 1 LAST MATERIAL X7R
J 0
(-5425 2475);
DISPLAY 0.489362 (-5425 2475);
PAINT SKYBLUE (-5425 2475);
FORCEPROP 1 LAST TOLERANCE 10%
J 0
(-5425 2525);
DISPLAY 0.489362 (-5425 2525);
PAINT SKYBLUE (-5425 2525);
FORCEPROP 1 LAST VALUE 0.1UF
J 0
(-5425 2625);
DISPLAY 0.489362 (-5425 2625);
PAINT SKYBLUE (-5425 2625);
FORCEPROP 1 LAST VOLTAGE 25V
J 0
(-5425 2575);
DISPLAY 0.489362 (-5425 2575);
PAINT SKYBLUE (-5425 2575);
FORCEPROP 2 LAST CDS_LIB pure_quanta
J 0
(-5475 2575);
DISPLAY INVISIBLE (-5475 2575);
FORCEPROP 1 LAST PATH I25
J 0
(-5425 2725);
DISPLAY 0.978723 (-5425 2725);
PAINT WHITE (-5425 2725);
DISPLAY INVISIBLE (-5425 2725);
FORCEPROP 1 LAST PART_NUMBER CH4104K1B00
J 0
(-5425 2425);
DISPLAY 0.489362 (-5425 2425);
PAINT SKYBLUE (-5425 2425);
DISPLAY INVISIBLE (-5425 2425);
FORCEADD Q_CAP..1
(-5150 2575);
FORCEPROP 1 LAST LOCATION PC263_2
J 0
(-5100 2675);
DISPLAY 0.489362 (-5100 2675);
PAINT SKYBLUE (-5100 2675);
FORCEPROP 0 LAST $SEC 1
J 0
(-5100 2700);
DISPLAY 0.680851 (-5100 2700);
PAINT MONO (-5100 2700);
DISPLAY INVISIBLE (-5100 2700);
FORCEPROP 0 LAST CDS_SEC 1
J 0
(-5100 2700);
DISPLAY 1.021277 (-5100 2700);
DISPLAY INVISIBLE (-5100 2700);
FORCEPROP 1 LASTPIN (-5150 2675) $PN 1
J 0
(-5140 2655);
DISPLAY 0.489362 (-5140 2655);
PAINT MONO (-5140 2655);
FORCEPROP 1 LASTPIN (-5150 2475) $PN 2
J 0
(-5140 2455);
DISPLAY 0.489362 (-5140 2455);
PAINT MONO (-5140 2455);
FORCEPROP 1 LAST MATERIAL X6S
J 0
(-5100 2475);
DISPLAY 0.489362 (-5100 2475);
PAINT SKYBLUE (-5100 2475);
FORCEPROP 1 LAST TOLERANCE 10%
J 0
(-5100 2525);
DISPLAY 0.489362 (-5100 2525);
PAINT SKYBLUE (-5100 2525);
FORCEPROP 1 LAST VALUE 1UF
J 0
(-5100 2625);
DISPLAY 0.489362 (-5100 2625);
PAINT SKYBLUE (-5100 2625);
FORCEPROP 1 LAST VOLTAGE 25V
J 0
(-5100 2575);
DISPLAY 0.489362 (-5100 2575);
PAINT SKYBLUE (-5100 2575);
FORCEPROP 1 LAST PACK_TYPE C0402
J 0
(-5100 2375);
DISPLAY 0.489362 (-5100 2375);
PAINT SKYBLUE (-5100 2375);
FORCEPROP 2 LAST CDS_LIB pure_quanta
J 0
(-5150 2575);
DISPLAY INVISIBLE (-5150 2575);
FORCEPROP 1 LAST PATH I26
J 0
(-5100 2725);
DISPLAY 0.978723 (-5100 2725);
PAINT WHITE (-5100 2725);
DISPLAY INVISIBLE (-5100 2725);
FORCEPROP 1 LAST PART_NUMBER CH5104KEB02
J 0
(-5100 2425);
DISPLAY 0.489362 (-5100 2425);
PAINT SKYBLUE (-5100 2425);
DISPLAY INVISIBLE (-5100 2425);
FORCEADD UNIVERSAL_GND..1
(-5550 3725);
FORCEPROP 3 LASTPIN (-5550 3775) SIG_NAME GND\g
J 0
(-5540 3785);
DISPLAY 0.659574 (-5540 3785);
PAINT MONO (-5540 3785);
DISPLAY INVISIBLE (-5540 3785);
FORCEPROP 2 LAST CDS_LIB pure_quanta_power
J 0
(-5550 3725);
DISPLAY INVISIBLE (-5550 3725);
FORCEPROP 1 LAST HDL_POWER GND
J 1
(-5525 3650);
DISPLAY 0.872340 (-5525 3650);
PAINT GREEN (-5525 3650);
DISPLAY INVISIBLE (-5525 3650);
FORCEPROP 1 LAST PATH I27
J 0
(-5475 3725);
DISPLAY 0.872340 (-5475 3725);
PAINT AQUA (-5475 3725);
DISPLAY INVISIBLE (-5475 3725);
FORCEADD Q_CAP..1
(-4825 2575);
FORCEPROP 1 LAST LOCATION PC265_2
J 0
(-4775 2675);
DISPLAY 0.489362 (-4775 2675);
PAINT SKYBLUE (-4775 2675);
FORCEPROP 0 LAST $SEC 1
J 0
(-4775 2700);
DISPLAY 0.680851 (-4775 2700);
PAINT MONO (-4775 2700);
DISPLAY INVISIBLE (-4775 2700);
FORCEPROP 0 LAST CDS_SEC 1
J 0
(-4775 2700);
DISPLAY 1.021277 (-4775 2700);
DISPLAY INVISIBLE (-4775 2700);
FORCEPROP 1 LASTPIN (-4825 2675) $PN 1
J 0
(-4815 2655);
DISPLAY 0.489362 (-4815 2655);
PAINT MONO (-4815 2655);
FORCEPROP 1 LASTPIN (-4825 2475) $PN 2
J 0
(-4815 2455);
DISPLAY 0.489362 (-4815 2455);
PAINT MONO (-4815 2455);
FORCEPROP 1 LAST TOLERANCE 20%
J 0
(-4775 2525);
DISPLAY 0.489362 (-4775 2525);
PAINT SKYBLUE (-4775 2525);
FORCEPROP 1 LAST MATERIAL X6S
J 0
(-4775 2475);
DISPLAY 0.489362 (-4775 2475);
PAINT SKYBLUE (-4775 2475);
FORCEPROP 1 LAST PACK_TYPE C0805
J 0
(-4775 2375);
DISPLAY 0.489362 (-4775 2375);
PAINT SKYBLUE (-4775 2375);
FORCEPROP 1 LAST VALUE 22UF
J 0
(-4775 2625);
DISPLAY 0.489362 (-4775 2625);
PAINT SKYBLUE (-4775 2625);
FORCEPROP 1 LAST VOLTAGE 16V
J 0
(-4775 2575);
DISPLAY 0.489362 (-4775 2575);
PAINT SKYBLUE (-4775 2575);
FORCEPROP 2 LAST CDS_LIB pure_quanta
J 0
(-4825 2575);
DISPLAY INVISIBLE (-4825 2575);
FORCEPROP 1 LAST PATH I28
J 0
(-4775 2725);
DISPLAY 0.978723 (-4775 2725);
PAINT WHITE (-4775 2725);
DISPLAY INVISIBLE (-4775 2725);
FORCEPROP 1 LAST PART_NUMBER CH6223MEA01
J 0
(-4775 2425);
DISPLAY 0.489362 (-4775 2425);
PAINT SKYBLUE (-4775 2425);
DISPLAY INVISIBLE (-4775 2425);
FORCEADD Q_CAP..1
(-4500 2575);
FORCEPROP 1 LAST LOCATION PC267_2
J 0
(-4450 2675);
DISPLAY 0.489362 (-4450 2675);
PAINT SKYBLUE (-4450 2675);
FORCEPROP 0 LAST $SEC 1
J 0
(-4450 2700);
DISPLAY 0.680851 (-4450 2700);
PAINT MONO (-4450 2700);
DISPLAY INVISIBLE (-4450 2700);
FORCEPROP 0 LAST CDS_SEC 1
J 0
(-4450 2700);
DISPLAY 1.021277 (-4450 2700);
DISPLAY INVISIBLE (-4450 2700);
FORCEPROP 1 LASTPIN (-4500 2675) $PN 1
J 0
(-4490 2655);
DISPLAY 0.489362 (-4490 2655);
PAINT MONO (-4490 2655);
FORCEPROP 1 LASTPIN (-4500 2475) $PN 2
J 0
(-4490 2455);
DISPLAY 0.489362 (-4490 2455);
PAINT MONO (-4490 2455);
FORCEPROP 1 LAST VALUE 22UF
J 0
(-4450 2625);
DISPLAY 0.489362 (-4450 2625);
PAINT SKYBLUE (-4450 2625);
FORCEPROP 1 LAST VOLTAGE 16V
J 0
(-4450 2575);
DISPLAY 0.489362 (-4450 2575);
PAINT SKYBLUE (-4450 2575);
FORCEPROP 1 LAST MATERIAL X6S
J 0
(-4450 2475);
DISPLAY 0.489362 (-4450 2475);
PAINT SKYBLUE (-4450 2475);
FORCEPROP 1 LAST PACK_TYPE C0805
J 0
(-4450 2375);
DISPLAY 0.489362 (-4450 2375);
PAINT SKYBLUE (-4450 2375);
FORCEPROP 1 LAST TOLERANCE 20%
J 0
(-4450 2525);
DISPLAY 0.489362 (-4450 2525);
PAINT SKYBLUE (-4450 2525);
FORCEPROP 2 LAST CDS_LIB pure_quanta
J 0
(-4500 2575);
DISPLAY INVISIBLE (-4500 2575);
FORCEPROP 1 LAST PATH I29
J 0
(-4450 2725);
DISPLAY 0.978723 (-4450 2725);
PAINT WHITE (-4450 2725);
DISPLAY INVISIBLE (-4450 2725);
FORCEPROP 1 LAST PART_NUMBER CH6223MEA01
J 0
(-4450 2425);
DISPLAY 0.489362 (-4450 2425);
PAINT SKYBLUE (-4450 2425);
DISPLAY INVISIBLE (-4450 2425);
FORCEADD Q_RES..1
R 1
(-8250 5750);
FORCEPROP 1 LAST LOCATION PR335
J 0
(-8225 5900);
DISPLAY 0.489362 (-8225 5900);
PAINT SKYBLUE (-8225 5900);
FORCEPROP 0 LAST $SEC 1
R 1
J 0
(-8225 5925);
DISPLAY 0.680851 (-8225 5925);
PAINT MONO (-8225 5925);
DISPLAY INVISIBLE (-8225 5925);
FORCEPROP 0 LAST CDS_SEC 1
R 1
J 0
(-8225 5925);
DISPLAY 1.021277 (-8225 5925);
DISPLAY INVISIBLE (-8225 5925);
FORCEPROP 1 LASTPIN (-8250 5650) $PN 1
R 1
J 0
(-8262 5662);
DISPLAY 0.787234 (-8262 5662);
PAINT MONO (-8262 5662);
DISPLAY INVISIBLE (-8262 5662);
FORCEPROP 1 LASTPIN (-8250 5850) $PN 2
R 1
J 0
(-8262 5812);
DISPLAY 0.787234 (-8262 5812);
PAINT MONO (-8262 5812);
DISPLAY INVISIBLE (-8262 5812);
FORCEPROP 1 LAST MATERIAL CHIP
J 0
(-8225 5700);
DISPLAY 0.489362 (-8225 5700);
PAINT SKYBLUE (-8225 5700);
FORCEPROP 1 LAST TOLERANCE 5%
J 0
(-8225 5800);
DISPLAY 0.489362 (-8225 5800);
PAINT SKYBLUE (-8225 5800);
FORCEPROP 1 LAST PACK_TYPE 0402LF
J 0
(-8225 5600);
DISPLAY 0.489362 (-8225 5600);
PAINT SKYBLUE (-8225 5600);
FORCEPROP 1 LAST VALUE 0
J 2
(-8200 5850);
DISPLAY 0.489362 (-8200 5850);
PAINT SKYBLUE (-8200 5850);
FORCEPROP 1 LAST WATTAGE 1/16W
J 0
(-8225 5750);
DISPLAY 0.489362 (-8225 5750);
PAINT SKYBLUE (-8225 5750);
FORCEPROP 2 LAST CDS_LIB pure_quanta
J 0
(-8250 5750);
DISPLAY INVISIBLE (-8250 5750);
FORCEPROP 1 LAST PATH I3
R 1
J 0
(-8400 5700);
DISPLAY 0.978723 (-8400 5700);
PAINT WHITE (-8400 5700);
DISPLAY INVISIBLE (-8400 5700);
FORCEPROP 1 LAST PART_NUMBER CS00002JB13
J 0
(-8225 5650);
DISPLAY 0.489362 (-8225 5650);
PAINT SKYBLUE (-8225 5650);
DISPLAY INVISIBLE (-8225 5650);
FORCEADD UNIVERSAL_GND..1
(-4200 2225);
FORCEPROP 3 LASTPIN (-4200 2275) SIG_NAME GND\g
J 0
(-4190 2285);
DISPLAY 0.659574 (-4190 2285);
PAINT MONO (-4190 2285);
DISPLAY INVISIBLE (-4190 2285);
FORCEPROP 2 LAST CDS_LIB pure_quanta_power
J 0
(-4200 2225);
DISPLAY INVISIBLE (-4200 2225);
FORCEPROP 1 LAST HDL_POWER GND
J 1
(-4175 2150);
DISPLAY 0.872340 (-4175 2150);
PAINT GREEN (-4175 2150);
DISPLAY INVISIBLE (-4175 2150);
FORCEPROP 1 LAST PATH I30
J 0
(-4125 2225);
DISPLAY 0.872340 (-4125 2225);
PAINT AQUA (-4125 2225);
DISPLAY INVISIBLE (-4125 2225);
FORCEADD Q_CAP..1
(-4200 2575);
FORCEPROP 1 LAST LOCATION PC269_2
J 0
(-4150 2675);
DISPLAY 0.489362 (-4150 2675);
PAINT SKYBLUE (-4150 2675);
FORCEPROP 0 LAST $SEC 1
J 0
(-4150 2700);
DISPLAY 0.680851 (-4150 2700);
PAINT MONO (-4150 2700);
DISPLAY INVISIBLE (-4150 2700);
FORCEPROP 0 LAST CDS_SEC 1
J 0
(-4150 2700);
DISPLAY 1.021277 (-4150 2700);
DISPLAY INVISIBLE (-4150 2700);
FORCEPROP 1 LASTPIN (-4200 2675) $PN 1
J 0
(-4190 2655);
DISPLAY 0.489362 (-4190 2655);
PAINT MONO (-4190 2655);
FORCEPROP 1 LASTPIN (-4200 2475) $PN 2
J 0
(-4190 2455);
DISPLAY 0.489362 (-4190 2455);
PAINT MONO (-4190 2455);
FORCEPROP 1 LAST PACK_TYPE C0805
J 0
(-4150 2375);
DISPLAY 0.489362 (-4150 2375);
PAINT SKYBLUE (-4150 2375);
FORCEPROP 1 LAST VOLTAGE 16V
J 0
(-4150 2575);
DISPLAY 0.489362 (-4150 2575);
PAINT SKYBLUE (-4150 2575);
FORCEPROP 1 LAST MATERIAL X6S
J 0
(-4150 2475);
DISPLAY 0.489362 (-4150 2475);
PAINT SKYBLUE (-4150 2475);
FORCEPROP 1 LAST VALUE 22UF
J 0
(-4150 2625);
DISPLAY 0.489362 (-4150 2625);
PAINT SKYBLUE (-4150 2625);
FORCEPROP 1 LAST TOLERANCE 20%
J 0
(-4150 2525);
DISPLAY 0.489362 (-4150 2525);
PAINT SKYBLUE (-4150 2525);
FORCEPROP 2 LAST CDS_LIB pure_quanta
J 0
(-4200 2575);
DISPLAY INVISIBLE (-4200 2575);
FORCEPROP 1 LAST PATH I31
J 0
(-4150 2725);
DISPLAY 0.978723 (-4150 2725);
PAINT WHITE (-4150 2725);
DISPLAY INVISIBLE (-4150 2725);
FORCEPROP 1 LAST PART_NUMBER CH6223MEA01
J 0
(-4150 2425);
DISPLAY 0.489362 (-4150 2425);
PAINT SKYBLUE (-4150 2425);
DISPLAY INVISIBLE (-4150 2425);
FORCEADD VCC_CORE..1
(-4200 2875);
FORCEPROP 3 LASTPIN (-4200 2825) SIG_NAME SW_P12V_AUX_PVDDCR_CPU0_P1_FLT\g
J 0
(-4190 2835);
DISPLAY 0.659574 (-4190 2835);
PAINT MONO (-4190 2835);
DISPLAY INVISIBLE (-4190 2835);
FORCEPROP 1 LAST HDL_POWER SW_P12V_AUX_PVDDCR_CPU0_P1_FLT
J 1
(-4200 2925);
DISPLAY 0.489362 (-4200 2925);
PAINT GREEN (-4200 2925);
FORCEPROP 2 LAST CDS_LIB pure_quanta_power
J 0
(-4200 2875);
DISPLAY INVISIBLE (-4200 2875);
FORCEPROP 1 LAST PATH I32
J 0
(-4150 2900);
DISPLAY 0.872340 (-4150 2900);
PAINT AQUA (-4150 2900);
DISPLAY INVISIBLE (-4150 2900);
FORCEADD UNIVERSAL_GND..1
(-4800 3550);
FORCEPROP 3 LASTPIN (-4800 3600) SIG_NAME GND\g
J 0
(-4790 3610);
DISPLAY 0.659574 (-4790 3610);
PAINT MONO (-4790 3610);
DISPLAY INVISIBLE (-4790 3610);
FORCEPROP 2 LAST CDS_LIB pure_quanta_power
J 0
(-4800 3550);
DISPLAY INVISIBLE (-4800 3550);
FORCEPROP 1 LAST HDL_POWER GND
J 1
(-4775 3475);
DISPLAY 0.872340 (-4775 3475);
PAINT GREEN (-4775 3475);
DISPLAY INVISIBLE (-4775 3475);
FORCEPROP 1 LAST PATH I33
J 0
(-4725 3550);
DISPLAY 0.872340 (-4725 3550);
PAINT AQUA (-4725 3550);
DISPLAY INVISIBLE (-4725 3550);
FORCEADD Q_RES..2
(-4800 3775);
FORCEPROP 1 LAST LOCATION PR485
J 0
(-4755 3900);
DISPLAY 0.489362 (-4755 3900);
PAINT SKYBLUE (-4755 3900);
FORCEPROP 0 LAST $SEC 1
J 0
(-4750 3950);
DISPLAY 0.680851 (-4750 3950);
PAINT MONO (-4750 3950);
DISPLAY INVISIBLE (-4750 3950);
FORCEPROP 0 LAST CDS_SEC 1
J 0
(-4750 3950);
DISPLAY 1.021277 (-4750 3950);
DISPLAY INVISIBLE (-4750 3950);
FORCEPROP 1 LASTPIN (-4800 3875) $PN 1
J 0
(-4795 3837);
DISPLAY 0.489362 (-4795 3837);
PAINT MONO (-4795 3837);
FORCEPROP 1 LASTPIN (-4800 3675) $PN 2
J 0
(-4795 3685);
DISPLAY 0.489362 (-4795 3685);
PAINT MONO (-4795 3685);
FORCEPROP 1 LAST MATERIAL EMPTY
J 0
(-4760 3700);
DISPLAY 0.489362 (-4760 3700);
PAINT RED (-4760 3700);
FORCEPROP 1 LAST PACK_TYPE 0402LF
J 0
(-4760 3600);
DISPLAY 0.489362 (-4760 3600);
PAINT SKYBLUE (-4760 3600);
FORCEPROP 1 LAST WATTAGE 1/8W
J 0
(-4760 3750);
DISPLAY 0.489362 (-4760 3750);
PAINT SKYBLUE (-4760 3750);
FORCEPROP 1 LAST TOLERANCE 1%
J 0
(-4755 3800);
DISPLAY 0.489362 (-4755 3800);
PAINT SKYBLUE (-4755 3800);
FORCEPROP 1 LAST VALUE 1.5
J 0
(-4755 3850);
DISPLAY 0.489362 (-4755 3850);
PAINT SKYBLUE (-4755 3850);
FORCEPROP 2 LAST CDS_LIB pure_quanta
J 0
(-4800 3775);
DISPLAY INVISIBLE (-4800 3775);
FORCEPROP 1 LAST PATH I34
J 0
(-4750 3950);
DISPLAY 0.978723 (-4750 3950);
PAINT WHITE (-4750 3950);
DISPLAY INVISIBLE (-4750 3950);
FORCEPROP 1 LAST PART_NUMBER CS-1504FB00
J 0
(-4760 3650);
DISPLAY 0.489362 (-4760 3650);
PAINT SKYBLUE (-4760 3650);
DISPLAY INVISIBLE (-4760 3650);
FORCEADD Q_RES..1
(-4325 3475);
FORCEPROP 1 LAST LOCATION PR191
J 0
(-4375 3525);
DISPLAY 0.489362 (-4375 3525);
PAINT SKYBLUE (-4375 3525);
FORCEPROP 0 LAST $SEC 1
J 0
(-4325 3550);
DISPLAY 0.680851 (-4325 3550);
PAINT MONO (-4325 3550);
DISPLAY INVISIBLE (-4325 3550);
FORCEPROP 0 LAST CDS_SEC 1
J 0
(-4325 3550);
DISPLAY 1.021277 (-4325 3550);
DISPLAY INVISIBLE (-4325 3550);
FORCEPROP 1 LASTPIN (-4425 3475) $PN 1
J 0
(-4413 3487);
DISPLAY 0.489362 (-4413 3487);
PAINT MONO (-4413 3487);
FORCEPROP 1 LASTPIN (-4225 3475) $PN 2
J 0
(-4263 3487);
DISPLAY 0.489362 (-4263 3487);
PAINT MONO (-4263 3487);
FORCEPROP 1 LAST WATTAGE 1/16W
J 0
(-4225 3425);
DISPLAY 0.489362 (-4225 3425);
PAINT SKYBLUE (-4225 3425);
FORCEPROP 1 LAST VALUE 0
J 2
(-4450 3500);
DISPLAY 0.489362 (-4450 3500);
PAINT SKYBLUE (-4450 3500);
FORCEPROP 1 LAST TOLERANCE 5%
J 0
(-4200 3500);
DISPLAY 0.489362 (-4200 3500);
PAINT SKYBLUE (-4200 3500);
FORCEPROP 1 LAST MATERIAL CHIP
J 0
(-4575 3375);
DISPLAY 0.489362 (-4575 3375);
PAINT SKYBLUE (-4575 3375);
FORCEPROP 1 LAST PACK_TYPE 0402LF
J 0
(-4225 3375);
DISPLAY 0.489362 (-4225 3375);
PAINT SKYBLUE (-4225 3375);
FORCEPROP 2 LAST CDS_LIB pure_quanta
J 0
(-4325 3475);
DISPLAY INVISIBLE (-4325 3475);
FORCEPROP 1 LAST PATH I35
J 0
(-4375 3625);
DISPLAY 0.978723 (-4375 3625);
PAINT WHITE (-4375 3625);
DISPLAY INVISIBLE (-4375 3625);
FORCEPROP 1 LAST PART_NUMBER CS00002JB13
J 0
(-4575 3425);
DISPLAY 0.489362 (-4575 3425);
PAINT SKYBLUE (-4575 3425);
DISPLAY INVISIBLE (-4575 3425);
FORCEADD Q_CAP..1
(-7600 4800);
FORCEPROP 1 LAST LOCATION PC256
J 0
(-7550 4900);
DISPLAY 0.489362 (-7550 4900);
PAINT SKYBLUE (-7550 4900);
FORCEPROP 0 LAST $SEC 1
J 0
(-7550 4925);
DISPLAY 0.680851 (-7550 4925);
PAINT MONO (-7550 4925);
DISPLAY INVISIBLE (-7550 4925);
FORCEPROP 0 LAST CDS_SEC 1
J 0
(-7550 4925);
DISPLAY 1.021277 (-7550 4925);
DISPLAY INVISIBLE (-7550 4925);
FORCEPROP 1 LASTPIN (-7600 4900) $PN 1
J 0
(-7590 4880);
DISPLAY 0.489362 (-7590 4880);
PAINT MONO (-7590 4880);
FORCEPROP 1 LASTPIN (-7600 4700) $PN 2
J 0
(-7590 4680);
DISPLAY 0.489362 (-7590 4680);
PAINT MONO (-7590 4680);
FORCEPROP 1 LAST MATERIAL X6S
J 0
(-7550 4700);
DISPLAY 0.489362 (-7550 4700);
PAINT SKYBLUE (-7550 4700);
FORCEPROP 1 LAST TOLERANCE 10%
J 0
(-7550 4750);
DISPLAY 0.489362 (-7550 4750);
PAINT SKYBLUE (-7550 4750);
FORCEPROP 1 LAST VALUE 2.2UF
J 0
(-7550 4850);
DISPLAY 0.489362 (-7550 4850);
PAINT SKYBLUE (-7550 4850);
FORCEPROP 1 LAST VOLTAGE 10V
J 0
(-7550 4800);
DISPLAY 0.489362 (-7550 4800);
PAINT SKYBLUE (-7550 4800);
FORCEPROP 1 LAST PACK_TYPE C0402
J 0
(-7550 4600);
DISPLAY 0.489362 (-7550 4600);
PAINT SKYBLUE (-7550 4600);
FORCEPROP 2 LAST CDS_LIB pure_quanta
J 0
(-7600 4800);
DISPLAY INVISIBLE (-7600 4800);
FORCEPROP 1 LAST PATH I36
J 0
(-7550 4950);
DISPLAY 0.978723 (-7550 4950);
PAINT WHITE (-7550 4950);
DISPLAY INVISIBLE (-7550 4950);
FORCEPROP 1 LAST PART_NUMBER CH5222KEB01
J 0
(-7550 4650);
DISPLAY 0.489362 (-7550 4650);
PAINT SKYBLUE (-7550 4650);
DISPLAY INVISIBLE (-7550 4650);
FORCEADD Q_RES..1
(-7300 4150);
FORCEPROP 1 LAST LOCATION PR187
J 0
(-7325 4200);
DISPLAY 0.489362 (-7325 4200);
PAINT SKYBLUE (-7325 4200);
FORCEPROP 0 LAST $SEC 1
J 0
(-7300 4225);
DISPLAY 0.680851 (-7300 4225);
PAINT MONO (-7300 4225);
DISPLAY INVISIBLE (-7300 4225);
FORCEPROP 0 LAST CDS_SEC 1
J 0
(-7300 4225);
DISPLAY 1.021277 (-7300 4225);
DISPLAY INVISIBLE (-7300 4225);
FORCEPROP 1 LASTPIN (-7400 4150) $PN 1
J 0
(-7388 4162);
DISPLAY 0.489362 (-7388 4162);
PAINT MONO (-7388 4162);
FORCEPROP 1 LASTPIN (-7200 4150) $PN 2
J 0
(-7238 4162);
DISPLAY 0.489362 (-7238 4162);
PAINT MONO (-7238 4162);
FORCEPROP 1 LAST PACK_TYPE 0402LF
J 0
(-7200 4100);
DISPLAY 0.489362 (-7200 4100);
PAINT SKYBLUE (-7200 4100);
FORCEPROP 1 LAST TOLERANCE 1%
J 0
(-7175 4175);
DISPLAY 0.489362 (-7175 4175);
PAINT SKYBLUE (-7175 4175);
FORCEPROP 1 LAST WATTAGE 1/16W
J 0
(-7200 4050);
DISPLAY 0.489362 (-7200 4050);
PAINT SKYBLUE (-7200 4050);
FORCEPROP 1 LAST MATERIAL EMPTY
J 0
(-7600 4050);
DISPLAY 0.489362 (-7600 4050);
PAINT RED (-7600 4050);
FORCEPROP 1 LAST VALUE 8.87K
J 2
(-7400 4175);
DISPLAY 0.489362 (-7400 4175);
PAINT SKYBLUE (-7400 4175);
FORCEPROP 2 LAST CDS_LIB pure_quanta
J 0
(-7300 4150);
DISPLAY INVISIBLE (-7300 4150);
FORCEPROP 1 LAST PATH I37
J 0
(-7350 4300);
DISPLAY 0.978723 (-7350 4300);
PAINT WHITE (-7350 4300);
DISPLAY INVISIBLE (-7350 4300);
FORCEPROP 1 LAST PART_NUMBER CS28872FB01
J 0
(-7600 4100);
DISPLAY 0.489362 (-7600 4100);
PAINT SKYBLUE (-7600 4100);
DISPLAY INVISIBLE (-7600 4100);
FORCEADD OFFPAGE..2
R 2
(-7275 4450);
FORCEPROP 2 LAST $XR0 210 
J 0
(-7530 4450);
DISPLAY 0.638298 (-7530 4450);
PAINT MONO (-7530 4450);
FORCEPROP 2 LAST CDS_LIB standard
J 2
(-7275 4450);
DISPLAY INVISIBLE (-7275 4450);
FORCEPROP 1 LAST OFFPAGE TRUE
J 2
(-7600 4325);
DISPLAY 0.872340 (-7600 4325);
PAINT GREEN (-7600 4325);
DISPLAY INVISIBLE (-7600 4325);
FORCEPROP 1 LAST COMMENT_BODY TRUE
J 2
(-7230 4355);
DISPLAY 0.872340 (-7230 4355);
PAINT GREEN (-7230 4355);
DISPLAY INVISIBLE (-7230 4355);
FORCEPROP 2 LAST PATH I38
J 0
(-7550 4500);
DISPLAY 0.680851 (-7550 4500);
DISPLAY INVISIBLE (-7550 4500);
FORCEADD UNIVERSAL_GND..1
(-7600 4600);
FORCEPROP 3 LASTPIN (-7600 4650) SIG_NAME GND\g
J 0
(-7590 4660);
DISPLAY 0.659574 (-7590 4660);
PAINT MONO (-7590 4660);
DISPLAY INVISIBLE (-7590 4660);
FORCEPROP 2 LAST CDS_LIB pure_quanta_power
J 0
(-7600 4600);
DISPLAY INVISIBLE (-7600 4600);
FORCEPROP 1 LAST HDL_POWER GND
J 1
(-7575 4525);
DISPLAY 0.872340 (-7575 4525);
PAINT GREEN (-7575 4525);
DISPLAY INVISIBLE (-7575 4525);
FORCEPROP 1 LAST PATH I39
J 0
(-7525 4600);
DISPLAY 0.872340 (-7525 4600);
PAINT AQUA (-7525 4600);
DISPLAY INVISIBLE (-7525 4600);
FORCEADD VCC_CORE..1
(-8250 5950);
FORCEPROP 3 LASTPIN (-8250 5900) SIG_NAME P5V_AUX\g
J 0
(-8240 5910);
DISPLAY 0.659574 (-8240 5910);
PAINT MONO (-8240 5910);
DISPLAY INVISIBLE (-8240 5910);
FORCEPROP 1 LAST HDL_POWER P5V_AUX
J 1
(-8250 6000);
DISPLAY 0.489362 (-8250 6000);
PAINT GREEN (-8250 6000);
FORCEPROP 2 LAST CDS_LIB pure_quanta_power
J 0
(-8250 5950);
DISPLAY INVISIBLE (-8250 5950);
FORCEPROP 1 LAST PATH I4
J 0
(-8200 5975);
DISPLAY 0.872340 (-8200 5975);
PAINT AQUA (-8200 5975);
DISPLAY INVISIBLE (-8200 5975);
FORCEADD UNIVERSAL_GND..1
(-7250 5100);
FORCEPROP 3 LASTPIN (-7250 5150) SIG_NAME GND\g
J 0
(-7240 5160);
DISPLAY 0.659574 (-7240 5160);
PAINT MONO (-7240 5160);
DISPLAY INVISIBLE (-7240 5160);
FORCEPROP 2 LAST CDS_LIB pure_quanta_power
J 0
(-7250 5100);
DISPLAY INVISIBLE (-7250 5100);
FORCEPROP 1 LAST HDL_POWER GND
J 1
(-7225 5025);
DISPLAY 0.872340 (-7225 5025);
PAINT GREEN (-7225 5025);
DISPLAY INVISIBLE (-7225 5025);
FORCEPROP 1 LAST PATH I40
J 0
(-7175 5100);
DISPLAY 0.872340 (-7175 5100);
PAINT AQUA (-7175 5100);
DISPLAY INVISIBLE (-7175 5100);
FORCEADD Q_RES..1
R 1
(-7900 5750);
FORCEPROP 1 LAST LOCATION PR336
J 0
(-7850 5900);
DISPLAY 0.489362 (-7850 5900);
PAINT SKYBLUE (-7850 5900);
FORCEPROP 0 LAST $SEC 1
R 1
J 0
(-7850 5925);
DISPLAY 0.680851 (-7850 5925);
PAINT MONO (-7850 5925);
DISPLAY INVISIBLE (-7850 5925);
FORCEPROP 0 LAST CDS_SEC 1
R 1
J 0
(-7850 5925);
DISPLAY 1.021277 (-7850 5925);
DISPLAY INVISIBLE (-7850 5925);
FORCEPROP 1 LASTPIN (-7900 5650) $PN 1
R 1
J 0
(-7912 5662);
DISPLAY 0.787234 (-7912 5662);
PAINT MONO (-7912 5662);
DISPLAY INVISIBLE (-7912 5662);
FORCEPROP 1 LASTPIN (-7900 5850) $PN 2
R 1
J 0
(-7912 5812);
DISPLAY 0.787234 (-7912 5812);
PAINT MONO (-7912 5812);
DISPLAY INVISIBLE (-7912 5812);
FORCEPROP 1 LAST TOLERANCE 5%
J 0
(-7850 5800);
DISPLAY 0.489362 (-7850 5800);
PAINT SKYBLUE (-7850 5800);
FORCEPROP 1 LAST VALUE 0
J 2
(-7825 5850);
DISPLAY 0.489362 (-7825 5850);
PAINT SKYBLUE (-7825 5850);
FORCEPROP 1 LAST PACK_TYPE 0402LF
J 0
(-7850 5600);
DISPLAY 0.489362 (-7850 5600);
PAINT SKYBLUE (-7850 5600);
FORCEPROP 1 LAST MATERIAL EMPTY
J 0
(-7850 5700);
DISPLAY 0.489362 (-7850 5700);
PAINT RED (-7850 5700);
FORCEPROP 1 LAST WATTAGE 1/16W
J 0
(-7850 5750);
DISPLAY 0.489362 (-7850 5750);
PAINT SKYBLUE (-7850 5750);
FORCEPROP 2 LAST CDS_LIB pure_quanta
J 0
(-7900 5750);
DISPLAY INVISIBLE (-7900 5750);
FORCEPROP 1 LAST PATH I41
R 1
J 0
(-8050 5700);
DISPLAY 0.978723 (-8050 5700);
PAINT WHITE (-8050 5700);
DISPLAY INVISIBLE (-8050 5700);
FORCEPROP 1 LAST PART_NUMBER CS00002JB13
J 0
(-7850 5650);
DISPLAY 0.489362 (-7850 5650);
PAINT SKYBLUE (-7850 5650);
DISPLAY INVISIBLE (-7850 5650);
FORCEADD VCC_CORE..1
(-7900 5950);
FORCEPROP 3 LASTPIN (-7900 5900) SIG_NAME P3V3_AUX\g
J 0
(-7890 5910);
DISPLAY 0.659574 (-7890 5910);
PAINT MONO (-7890 5910);
DISPLAY INVISIBLE (-7890 5910);
FORCEPROP 1 LAST HDL_POWER P3V3_AUX
J 1
(-7900 6000);
DISPLAY 0.489362 (-7900 6000);
PAINT GREEN (-7900 6000);
FORCEPROP 2 LAST CDS_LIB pure_quanta_power
J 0
(-7900 5950);
DISPLAY INVISIBLE (-7900 5950);
FORCEPROP 1 LAST PATH I42
J 0
(-7850 5975);
DISPLAY 0.872340 (-7850 5975);
PAINT AQUA (-7850 5975);
DISPLAY INVISIBLE (-7850 5975);
FORCEADD Q_RES..2
(-7600 5350);
FORCEPROP 1 LAST LOCATION PR185
J 0
(-7550 5475);
DISPLAY 0.489362 (-7550 5475);
PAINT SKYBLUE (-7550 5475);
FORCEPROP 0 LAST $SEC 1
J 0
(-7550 5500);
DISPLAY 0.680851 (-7550 5500);
PAINT MONO (-7550 5500);
DISPLAY INVISIBLE (-7550 5500);
FORCEPROP 0 LAST CDS_SEC 1
J 0
(-7550 5500);
DISPLAY 1.021277 (-7550 5500);
DISPLAY INVISIBLE (-7550 5500);
FORCEPROP 1 LASTPIN (-7600 5450) $PN 1
J 0
(-7595 5412);
DISPLAY 0.489362 (-7595 5412);
PAINT MONO (-7595 5412);
FORCEPROP 1 LASTPIN (-7600 5250) $PN 2
J 0
(-7595 5260);
DISPLAY 0.489362 (-7595 5260);
PAINT MONO (-7595 5260);
FORCEPROP 1 LAST PACK_TYPE 0402LF
J 0
(-7550 5175);
DISPLAY 0.489362 (-7550 5175);
PAINT SKYBLUE (-7550 5175);
FORCEPROP 1 LAST VALUE 2.2
J 0
(-7550 5425);
DISPLAY 0.489362 (-7550 5425);
PAINT SKYBLUE (-7550 5425);
FORCEPROP 1 LAST TOLERANCE 1%
J 0
(-7550 5375);
DISPLAY 0.489362 (-7550 5375);
PAINT SKYBLUE (-7550 5375);
FORCEPROP 1 LAST MATERIAL CHIP
J 0
(-7550 5275);
DISPLAY 0.489362 (-7550 5275);
PAINT SKYBLUE (-7550 5275);
FORCEPROP 1 LAST WATTAGE 1/16W
J 0
(-7550 5325);
DISPLAY 0.489362 (-7550 5325);
PAINT SKYBLUE (-7550 5325);
FORCEPROP 2 LAST CDS_LIB pure_quanta
J 0
(-7600 5350);
DISPLAY INVISIBLE (-7600 5350);
FORCEPROP 1 LAST PATH I43
J 0
(-7550 5525);
DISPLAY 0.978723 (-7550 5525);
PAINT WHITE (-7550 5525);
DISPLAY INVISIBLE (-7550 5525);
FORCEPROP 1 LAST PART_NUMBER CS-2202FB01
J 0
(-7550 5225);
DISPLAY 0.489362 (-7550 5225);
PAINT SKYBLUE (-7550 5225);
DISPLAY INVISIBLE (-7550 5225);
FORCEADD Q_CAP..1
(-7250 5375);
FORCEPROP 1 LAST LOCATION PC258_C0P1_1
J 0
(-7200 5475);
DISPLAY 0.489362 (-7200 5475);
PAINT SKYBLUE (-7200 5475);
FORCEPROP 0 LAST $SEC 1
J 0
(-7200 5500);
DISPLAY 0.680851 (-7200 5500);
PAINT MONO (-7200 5500);
DISPLAY INVISIBLE (-7200 5500);
FORCEPROP 0 LAST CDS_SEC 1
J 0
(-7200 5500);
DISPLAY 1.021277 (-7200 5500);
DISPLAY INVISIBLE (-7200 5500);
FORCEPROP 1 LASTPIN (-7250 5475) $PN 1
J 0
(-7240 5455);
DISPLAY 0.489362 (-7240 5455);
PAINT MONO (-7240 5455);
FORCEPROP 1 LASTPIN (-7250 5275) $PN 2
J 0
(-7240 5255);
DISPLAY 0.489362 (-7240 5255);
PAINT MONO (-7240 5255);
FORCEPROP 1 LAST TOLERANCE 10%
J 0
(-7200 5325);
DISPLAY 0.489362 (-7200 5325);
PAINT SKYBLUE (-7200 5325);
FORCEPROP 1 LAST MATERIAL X6S
J 0
(-7200 5275);
DISPLAY 0.489362 (-7200 5275);
PAINT SKYBLUE (-7200 5275);
FORCEPROP 1 LAST VALUE 2.2UF
J 0
(-7200 5425);
DISPLAY 0.489362 (-7200 5425);
PAINT SKYBLUE (-7200 5425);
FORCEPROP 1 LAST VOLTAGE 10V
J 0
(-7200 5375);
DISPLAY 0.489362 (-7200 5375);
PAINT SKYBLUE (-7200 5375);
FORCEPROP 1 LAST PACK_TYPE C0402
J 0
(-7200 5175);
DISPLAY 0.489362 (-7200 5175);
PAINT SKYBLUE (-7200 5175);
FORCEPROP 2 LAST CDS_LIB pure_quanta
J 0
(-7250 5375);
DISPLAY INVISIBLE (-7250 5375);
FORCEPROP 1 LAST PATH I44
J 0
(-7200 5525);
DISPLAY 0.978723 (-7200 5525);
PAINT WHITE (-7200 5525);
DISPLAY INVISIBLE (-7200 5525);
FORCEPROP 1 LAST PART_NUMBER CH5222KEB01
J 0
(-7200 5225);
DISPLAY 0.489362 (-7200 5225);
PAINT SKYBLUE (-7200 5225);
DISPLAY INVISIBLE (-7200 5225);
FORCEADD VCC_CORE..1
(-7425 5950);
FORCEPROP 3 LASTPIN (-7425 5900) SIG_NAME PVDDCR_CPU0_P1_PVCC\g
J 0
(-7415 5910);
DISPLAY 0.659574 (-7415 5910);
PAINT MONO (-7415 5910);
DISPLAY INVISIBLE (-7415 5910);
FORCEPROP 1 LAST HDL_POWER PVDDCR_CPU0_P1_PVCC
J 1
(-7425 6000);
DISPLAY 0.489362 (-7425 6000);
PAINT GREEN (-7425 6000);
FORCEPROP 2 LAST CDS_LIB pure_quanta_power
J 0
(-7425 5950);
DISPLAY INVISIBLE (-7425 5950);
FORCEPROP 1 LAST PATH I45
J 0
(-7375 5975);
DISPLAY 0.872340 (-7375 5975);
PAINT AQUA (-7375 5975);
DISPLAY INVISIBLE (-7375 5975);
FORCEADD Q_CAP..1
(-5475 5325);
FORCEPROP 1 LAST LOCATION PC260_1
J 0
(-5425 5425);
DISPLAY 0.489362 (-5425 5425);
PAINT SKYBLUE (-5425 5425);
FORCEPROP 0 LAST $SEC 1
J 0
(-5425 5450);
DISPLAY 0.680851 (-5425 5450);
PAINT MONO (-5425 5450);
DISPLAY INVISIBLE (-5425 5450);
FORCEPROP 0 LAST CDS_SEC 1
J 0
(-5425 5450);
DISPLAY 1.021277 (-5425 5450);
DISPLAY INVISIBLE (-5425 5450);
FORCEPROP 1 LASTPIN (-5475 5425) $PN 1
J 0
(-5465 5405);
DISPLAY 0.489362 (-5465 5405);
PAINT MONO (-5465 5405);
FORCEPROP 1 LASTPIN (-5475 5225) $PN 2
J 0
(-5465 5205);
DISPLAY 0.489362 (-5465 5205);
PAINT MONO (-5465 5205);
FORCEPROP 1 LAST MATERIAL X7R
J 0
(-5425 5225);
DISPLAY 0.489362 (-5425 5225);
PAINT SKYBLUE (-5425 5225);
FORCEPROP 1 LAST PACK_TYPE 0402
J 0
(-5425 5125);
DISPLAY 0.489362 (-5425 5125);
PAINT SKYBLUE (-5425 5125);
FORCEPROP 1 LAST VALUE 0.1UF
J 0
(-5425 5375);
DISPLAY 0.489362 (-5425 5375);
PAINT SKYBLUE (-5425 5375);
FORCEPROP 1 LAST TOLERANCE 10%
J 0
(-5425 5275);
DISPLAY 0.489362 (-5425 5275);
PAINT SKYBLUE (-5425 5275);
FORCEPROP 1 LAST VOLTAGE 25V
J 0
(-5425 5325);
DISPLAY 0.489362 (-5425 5325);
PAINT SKYBLUE (-5425 5325);
FORCEPROP 2 LAST CDS_LIB pure_quanta
J 0
(-5475 5325);
DISPLAY INVISIBLE (-5475 5325);
FORCEPROP 1 LAST PATH I46
J 0
(-5425 5475);
DISPLAY 0.978723 (-5425 5475);
PAINT WHITE (-5425 5475);
DISPLAY INVISIBLE (-5425 5475);
FORCEPROP 1 LAST PART_NUMBER CH4104K1B00
J 0
(-5425 5175);
DISPLAY 0.489362 (-5425 5175);
PAINT SKYBLUE (-5425 5175);
DISPLAY INVISIBLE (-5425 5175);
FORCEADD Q_CAP..1
(-5150 5325);
FORCEPROP 1 LAST LOCATION PC262_1
J 0
(-5100 5425);
DISPLAY 0.489362 (-5100 5425);
PAINT SKYBLUE (-5100 5425);
FORCEPROP 0 LAST $SEC 1
J 0
(-5100 5450);
DISPLAY 0.680851 (-5100 5450);
PAINT MONO (-5100 5450);
DISPLAY INVISIBLE (-5100 5450);
FORCEPROP 0 LAST CDS_SEC 1
J 0
(-5100 5450);
DISPLAY 1.021277 (-5100 5450);
DISPLAY INVISIBLE (-5100 5450);
FORCEPROP 1 LASTPIN (-5150 5425) $PN 1
J 0
(-5140 5405);
DISPLAY 0.489362 (-5140 5405);
PAINT MONO (-5140 5405);
FORCEPROP 1 LASTPIN (-5150 5225) $PN 2
J 0
(-5140 5205);
DISPLAY 0.489362 (-5140 5205);
PAINT MONO (-5140 5205);
FORCEPROP 1 LAST VALUE 1UF
J 0
(-5100 5375);
DISPLAY 0.489362 (-5100 5375);
PAINT SKYBLUE (-5100 5375);
FORCEPROP 1 LAST TOLERANCE 10%
J 0
(-5100 5275);
DISPLAY 0.489362 (-5100 5275);
PAINT SKYBLUE (-5100 5275);
FORCEPROP 1 LAST PACK_TYPE C0402
J 0
(-5100 5125);
DISPLAY 0.489362 (-5100 5125);
PAINT SKYBLUE (-5100 5125);
FORCEPROP 1 LAST VOLTAGE 25V
J 0
(-5100 5325);
DISPLAY 0.489362 (-5100 5325);
PAINT SKYBLUE (-5100 5325);
FORCEPROP 1 LAST MATERIAL X6S
J 0
(-5100 5225);
DISPLAY 0.489362 (-5100 5225);
PAINT SKYBLUE (-5100 5225);
FORCEPROP 2 LAST CDS_LIB pure_quanta
J 0
(-5150 5325);
DISPLAY INVISIBLE (-5150 5325);
FORCEPROP 1 LAST PATH I47
J 0
(-5100 5475);
DISPLAY 0.978723 (-5100 5475);
PAINT WHITE (-5100 5475);
DISPLAY INVISIBLE (-5100 5475);
FORCEPROP 1 LAST PART_NUMBER CH5104KEB02
J 0
(-5100 5175);
DISPLAY 0.489362 (-5100 5175);
PAINT SKYBLUE (-5100 5175);
DISPLAY INVISIBLE (-5100 5175);
FORCEADD Q_CAP..1
(-4800 4250);
FORCEPROP 1 LAST LOCATION PC170
J 0
(-4750 4350);
DISPLAY 0.489362 (-4750 4350);
PAINT SKYBLUE (-4750 4350);
FORCEPROP 0 LAST $SEC 1
J 0
(-4750 4400);
DISPLAY 0.680851 (-4750 4400);
PAINT MONO (-4750 4400);
DISPLAY INVISIBLE (-4750 4400);
FORCEPROP 0 LAST CDS_SEC 1
J 0
(-4750 4400);
DISPLAY 1.021277 (-4750 4400);
DISPLAY INVISIBLE (-4750 4400);
FORCEPROP 1 LASTPIN (-4800 4350) $PN 1
J 0
(-4790 4330);
DISPLAY 0.489362 (-4790 4330);
PAINT MONO (-4790 4330);
FORCEPROP 1 LASTPIN (-4800 4150) $PN 2
J 0
(-4790 4130);
DISPLAY 0.489362 (-4790 4130);
PAINT MONO (-4790 4130);
FORCEPROP 1 LAST PACK_TYPE C0402
J 0
(-4750 4050);
DISPLAY 0.489362 (-4750 4050);
PAINT SKYBLUE (-4750 4050);
FORCEPROP 1 LAST TOLERANCE 10%
J 0
(-4750 4200);
DISPLAY 0.489362 (-4750 4200);
PAINT SKYBLUE (-4750 4200);
FORCEPROP 1 LAST MATERIAL EMPTY
J 0
(-4750 4150);
DISPLAY 0.489362 (-4750 4150);
PAINT RED (-4750 4150);
FORCEPROP 1 LAST VOLTAGE 50V
J 0
(-4750 4250);
DISPLAY 0.489362 (-4750 4250);
PAINT SKYBLUE (-4750 4250);
FORCEPROP 1 LAST VALUE 560PF
J 0
(-4750 4300);
DISPLAY 0.489362 (-4750 4300);
PAINT SKYBLUE (-4750 4300);
FORCEPROP 2 LAST CDS_LIB pure_quanta
J 0
(-4800 4250);
DISPLAY INVISIBLE (-4800 4250);
FORCEPROP 1 LAST PATH I48
J 0
(-4750 4400);
DISPLAY 0.978723 (-4750 4400);
PAINT WHITE (-4750 4400);
DISPLAY INVISIBLE (-4750 4400);
FORCEPROP 1 LAST PART_NUMBER CH1566K1B09
J 0
(-4750 4100);
DISPLAY 0.489362 (-4750 4100);
PAINT SKYBLUE (-4750 4100);
DISPLAY INVISIBLE (-4750 4100);
FORCEADD Q_RES..1
(-4875 4800);
FORCEPROP 1 LAST LOCATION PR189
J 0
(-4925 4850);
DISPLAY 0.489362 (-4925 4850);
PAINT SKYBLUE (-4925 4850);
FORCEPROP 0 LAST $SEC 1
J 0
(-4850 4875);
DISPLAY 0.680851 (-4850 4875);
PAINT MONO (-4850 4875);
DISPLAY INVISIBLE (-4850 4875);
FORCEPROP 0 LAST CDS_SEC 1
J 0
(-4850 4875);
DISPLAY 1.021277 (-4850 4875);
DISPLAY INVISIBLE (-4850 4875);
FORCEPROP 1 LASTPIN (-4975 4800) $PN 1
J 0
(-4963 4812);
DISPLAY 0.489362 (-4963 4812);
PAINT MONO (-4963 4812);
FORCEPROP 1 LASTPIN (-4775 4800) $PN 2
J 0
(-4813 4812);
DISPLAY 0.489362 (-4813 4812);
PAINT MONO (-4813 4812);
FORCEPROP 1 LAST TOLERANCE 1%
J 0
(-4775 4825);
DISPLAY 0.489362 (-4775 4825);
PAINT SKYBLUE (-4775 4825);
FORCEPROP 1 LAST PACK_TYPE 0402LF
J 0
(-4775 4700);
DISPLAY 0.489362 (-4775 4700);
PAINT SKYBLUE (-4775 4700);
FORCEPROP 1 LAST WATTAGE 1/16W
J 0
(-4775 4750);
DISPLAY 0.489362 (-4775 4750);
PAINT SKYBLUE (-4775 4750);
FORCEPROP 1 LAST MATERIAL CHIP
J 0
(-5125 4700);
DISPLAY 0.489362 (-5125 4700);
PAINT SKYBLUE (-5125 4700);
FORCEPROP 1 LAST VALUE 5.6
J 2
(-4975 4825);
DISPLAY 0.489362 (-4975 4825);
PAINT SKYBLUE (-4975 4825);
FORCEPROP 2 LAST CDS_LIB pure_quanta
J 0
(-4875 4800);
DISPLAY INVISIBLE (-4875 4800);
FORCEPROP 1 LAST PATH I49
J 0
(-4925 4950);
DISPLAY 0.978723 (-4925 4950);
PAINT WHITE (-4925 4950);
DISPLAY INVISIBLE (-4925 4950);
FORCEPROP 1 LAST PART_NUMBER CS-5602FB01
J 0
(-5125 4750);
DISPLAY 0.489362 (-5125 4750);
PAINT SKYBLUE (-5125 4750);
DISPLAY INVISIBLE (-5125 4750);
FORCEADD Q_CAP..1
(-7925 1425);
FORCEPROP 1 LAST LOCATION PC255_2
J 0
(-7875 1525);
DISPLAY 0.489362 (-7875 1525);
PAINT SKYBLUE (-7875 1525);
FORCEPROP 0 LAST $SEC 1
J 0
(-7875 1550);
DISPLAY 0.680851 (-7875 1550);
PAINT MONO (-7875 1550);
DISPLAY INVISIBLE (-7875 1550);
FORCEPROP 0 LAST CDS_SEC 1
J 0
(-7875 1550);
DISPLAY 1.021277 (-7875 1550);
DISPLAY INVISIBLE (-7875 1550);
FORCEPROP 1 LASTPIN (-7925 1525) $PN 1
J 0
(-7915 1505);
DISPLAY 0.489362 (-7915 1505);
PAINT MONO (-7915 1505);
FORCEPROP 1 LASTPIN (-7925 1325) $PN 2
J 0
(-7915 1305);
DISPLAY 0.489362 (-7915 1305);
PAINT MONO (-7915 1305);
FORCEPROP 1 LAST MATERIAL X7R
J 0
(-7875 1325);
DISPLAY 0.489362 (-7875 1325);
PAINT SKYBLUE (-7875 1325);
FORCEPROP 1 LAST TOLERANCE 10%
J 0
(-7875 1375);
DISPLAY 0.489362 (-7875 1375);
PAINT SKYBLUE (-7875 1375);
FORCEPROP 1 LAST VOLTAGE 25V
J 0
(-7875 1425);
DISPLAY 0.489362 (-7875 1425);
PAINT SKYBLUE (-7875 1425);
FORCEPROP 1 LAST PACK_TYPE 0402
J 0
(-7875 1225);
DISPLAY 0.489362 (-7875 1225);
PAINT SKYBLUE (-7875 1225);
FORCEPROP 1 LAST VALUE 0.1UF
J 0
(-7875 1475);
DISPLAY 0.489362 (-7875 1475);
PAINT SKYBLUE (-7875 1475);
FORCEPROP 2 LAST CDS_LIB pure_quanta
J 0
(-7925 1425);
DISPLAY INVISIBLE (-7925 1425);
FORCEPROP 1 LAST PATH I5
J 0
(-7875 1575);
DISPLAY 0.978723 (-7875 1575);
PAINT WHITE (-7875 1575);
DISPLAY INVISIBLE (-7875 1575);
FORCEPROP 1 LAST PART_NUMBER CH4104K1B00
J 0
(-7875 1275);
DISPLAY 0.489362 (-7875 1275);
PAINT SKYBLUE (-7875 1275);
DISPLAY INVISIBLE (-7875 1275);
FORCEADD OFFPAGE..3
R 2
(-4250 4200);
FORCEPROP 2 LAST $XR0 213 
J 0
(-4560 4200);
DISPLAY 0.638298 (-4560 4200);
PAINT MONO (-4560 4200);
FORCEPROP 2 LAST CDS_LIB standard
J 0
(-4250 4200);
DISPLAY INVISIBLE (-4250 4200);
FORCEPROP 1 LAST OFFPAGE TRUE
J 2
(-4575 4075);
DISPLAY 0.872340 (-4575 4075);
PAINT GREEN (-4575 4075);
DISPLAY INVISIBLE (-4575 4075);
FORCEPROP 1 LAST COMMENT_BODY TRUE
J 2
(-4200 4100);
DISPLAY 0.872340 (-4200 4100);
PAINT GREEN (-4200 4100);
DISPLAY INVISIBLE (-4200 4100);
FORCEPROP 2 LAST PATH I50
J 0
(-4525 4250);
DISPLAY 0.680851 (-4525 4250);
DISPLAY INVISIBLE (-4525 4250);
FORCEADD Q_CAP..1
(-4825 5325);
FORCEPROP 1 LAST LOCATION PC264_1
J 0
(-4775 5425);
DISPLAY 0.489362 (-4775 5425);
PAINT SKYBLUE (-4775 5425);
FORCEPROP 0 LAST $SEC 1
J 0
(-4775 5450);
DISPLAY 0.680851 (-4775 5450);
PAINT MONO (-4775 5450);
DISPLAY INVISIBLE (-4775 5450);
FORCEPROP 0 LAST CDS_SEC 1
J 0
(-4775 5450);
DISPLAY 1.021277 (-4775 5450);
DISPLAY INVISIBLE (-4775 5450);
FORCEPROP 1 LASTPIN (-4825 5425) $PN 1
J 0
(-4815 5405);
DISPLAY 0.489362 (-4815 5405);
PAINT MONO (-4815 5405);
FORCEPROP 1 LASTPIN (-4825 5225) $PN 2
J 0
(-4815 5205);
DISPLAY 0.489362 (-4815 5205);
PAINT MONO (-4815 5205);
FORCEPROP 1 LAST PACK_TYPE C0805
J 0
(-4775 5125);
DISPLAY 0.489362 (-4775 5125);
PAINT SKYBLUE (-4775 5125);
FORCEPROP 1 LAST MATERIAL X6S
J 0
(-4775 5225);
DISPLAY 0.489362 (-4775 5225);
PAINT SKYBLUE (-4775 5225);
FORCEPROP 1 LAST VALUE 22UF
J 0
(-4775 5375);
DISPLAY 0.489362 (-4775 5375);
PAINT SKYBLUE (-4775 5375);
FORCEPROP 1 LAST VOLTAGE 16V
J 0
(-4775 5325);
DISPLAY 0.489362 (-4775 5325);
PAINT SKYBLUE (-4775 5325);
FORCEPROP 1 LAST TOLERANCE 20%
J 0
(-4775 5275);
DISPLAY 0.489362 (-4775 5275);
PAINT SKYBLUE (-4775 5275);
FORCEPROP 2 LAST CDS_LIB pure_quanta
J 0
(-4825 5325);
DISPLAY INVISIBLE (-4825 5325);
FORCEPROP 1 LAST PATH I51
J 0
(-4775 5475);
DISPLAY 0.978723 (-4775 5475);
PAINT WHITE (-4775 5475);
DISPLAY INVISIBLE (-4775 5475);
FORCEPROP 1 LAST PART_NUMBER CH6223MEA01
J 0
(-4775 5175);
DISPLAY 0.489362 (-4775 5175);
PAINT SKYBLUE (-4775 5175);
DISPLAY INVISIBLE (-4775 5175);
FORCEADD Q_CAP..1
(-4500 5325);
FORCEPROP 1 LAST LOCATION PC266_1
J 0
(-4450 5425);
DISPLAY 0.489362 (-4450 5425);
PAINT SKYBLUE (-4450 5425);
FORCEPROP 0 LAST $SEC 1
J 0
(-4450 5450);
DISPLAY 0.680851 (-4450 5450);
PAINT MONO (-4450 5450);
DISPLAY INVISIBLE (-4450 5450);
FORCEPROP 0 LAST CDS_SEC 1
J 0
(-4450 5450);
DISPLAY 1.021277 (-4450 5450);
DISPLAY INVISIBLE (-4450 5450);
FORCEPROP 1 LASTPIN (-4500 5425) $PN 1
J 0
(-4490 5405);
DISPLAY 0.489362 (-4490 5405);
PAINT MONO (-4490 5405);
FORCEPROP 1 LASTPIN (-4500 5225) $PN 2
J 0
(-4490 5205);
DISPLAY 0.489362 (-4490 5205);
PAINT MONO (-4490 5205);
FORCEPROP 1 LAST PACK_TYPE C0805
J 0
(-4450 5125);
DISPLAY 0.489362 (-4450 5125);
PAINT SKYBLUE (-4450 5125);
FORCEPROP 1 LAST MATERIAL X6S
J 0
(-4450 5225);
DISPLAY 0.489362 (-4450 5225);
PAINT SKYBLUE (-4450 5225);
FORCEPROP 1 LAST VALUE 22UF
J 0
(-4450 5375);
DISPLAY 0.489362 (-4450 5375);
PAINT SKYBLUE (-4450 5375);
FORCEPROP 1 LAST VOLTAGE 16V
J 0
(-4450 5325);
DISPLAY 0.489362 (-4450 5325);
PAINT SKYBLUE (-4450 5325);
FORCEPROP 1 LAST TOLERANCE 20%
J 0
(-4450 5275);
DISPLAY 0.489362 (-4450 5275);
PAINT SKYBLUE (-4450 5275);
FORCEPROP 2 LAST CDS_LIB pure_quanta
J 0
(-4500 5325);
DISPLAY INVISIBLE (-4500 5325);
FORCEPROP 1 LAST PATH I52
J 0
(-4450 5475);
DISPLAY 0.978723 (-4450 5475);
PAINT WHITE (-4450 5475);
DISPLAY INVISIBLE (-4450 5475);
FORCEPROP 1 LAST PART_NUMBER CH6223MEA01
J 0
(-4450 5175);
DISPLAY 0.489362 (-4450 5175);
PAINT SKYBLUE (-4450 5175);
DISPLAY INVISIBLE (-4450 5175);
FORCEADD Q_CAP..1
(-4200 5325);
FORCEPROP 1 LAST LOCATION PC268_1
J 0
(-4150 5425);
DISPLAY 0.489362 (-4150 5425);
PAINT SKYBLUE (-4150 5425);
FORCEPROP 0 LAST $SEC 1
J 0
(-4150 5450);
DISPLAY 0.680851 (-4150 5450);
PAINT MONO (-4150 5450);
DISPLAY INVISIBLE (-4150 5450);
FORCEPROP 0 LAST CDS_SEC 1
J 0
(-4150 5450);
DISPLAY 1.021277 (-4150 5450);
DISPLAY INVISIBLE (-4150 5450);
FORCEPROP 1 LASTPIN (-4200 5425) $PN 1
J 0
(-4190 5405);
DISPLAY 0.489362 (-4190 5405);
PAINT MONO (-4190 5405);
FORCEPROP 1 LASTPIN (-4200 5225) $PN 2
J 0
(-4190 5205);
DISPLAY 0.489362 (-4190 5205);
PAINT MONO (-4190 5205);
FORCEPROP 1 LAST PACK_TYPE C0805
J 0
(-4150 5125);
DISPLAY 0.489362 (-4150 5125);
PAINT SKYBLUE (-4150 5125);
FORCEPROP 1 LAST VALUE 22UF
J 0
(-4150 5375);
DISPLAY 0.489362 (-4150 5375);
PAINT SKYBLUE (-4150 5375);
FORCEPROP 1 LAST MATERIAL X6S
J 0
(-4150 5225);
DISPLAY 0.489362 (-4150 5225);
PAINT SKYBLUE (-4150 5225);
FORCEPROP 1 LAST TOLERANCE 20%
J 0
(-4150 5275);
DISPLAY 0.489362 (-4150 5275);
PAINT SKYBLUE (-4150 5275);
FORCEPROP 1 LAST VOLTAGE 16V
J 0
(-4150 5325);
DISPLAY 0.489362 (-4150 5325);
PAINT SKYBLUE (-4150 5325);
FORCEPROP 2 LAST CDS_LIB pure_quanta
J 0
(-4200 5325);
DISPLAY INVISIBLE (-4200 5325);
FORCEPROP 1 LAST PATH I53
J 0
(-4150 5475);
DISPLAY 0.978723 (-4150 5475);
PAINT WHITE (-4150 5475);
DISPLAY INVISIBLE (-4150 5475);
FORCEPROP 1 LAST PART_NUMBER CH6223MEA01
J 0
(-4150 5175);
DISPLAY 0.489362 (-4150 5175);
PAINT SKYBLUE (-4150 5175);
DISPLAY INVISIBLE (-4150 5175);
FORCEADD OFFPAGE..3
R 2
(-3775 1450);
FORCEPROP 2 LAST $XR0 211 
J 0
(-4055 1450);
DISPLAY 0.638298 (-4055 1450);
PAINT MONO (-4055 1450);
FORCEPROP 2 LAST CDS_LIB standard
J 2
(-3775 1450);
DISPLAY INVISIBLE (-3775 1450);
FORCEPROP 1 LAST OFFPAGE TRUE
J 2
(-4100 1325);
DISPLAY 0.872340 (-4100 1325);
PAINT GREEN (-4100 1325);
DISPLAY INVISIBLE (-4100 1325);
FORCEPROP 1 LAST COMMENT_BODY TRUE
J 2
(-3725 1350);
DISPLAY 0.872340 (-3725 1350);
PAINT GREEN (-3725 1350);
DISPLAY INVISIBLE (-3725 1350);
FORCEPROP 2 LAST PATH I54
J 0
(-4050 1500);
DISPLAY 0.680851 (-4050 1500);
DISPLAY INVISIBLE (-4050 1500);
FORCEADD Q_CAP..1
(-3675 1925);
FORCEPROP 1 LAST LOCATION PC271
J 0
(-3625 2050);
DISPLAY 0.489362 (-3625 2050);
PAINT SKYBLUE (-3625 2050);
FORCEPROP 0 LAST $SEC 1
J 0
(-3625 2075);
DISPLAY 0.680851 (-3625 2075);
PAINT MONO (-3625 2075);
DISPLAY INVISIBLE (-3625 2075);
FORCEPROP 0 LAST CDS_SEC 1
J 0
(-3625 2075);
DISPLAY 1.021277 (-3625 2075);
DISPLAY INVISIBLE (-3625 2075);
FORCEPROP 1 LASTPIN (-3675 2025) $PN 1
J 0
(-3665 2005);
DISPLAY 0.489362 (-3665 2005);
PAINT MONO (-3665 2005);
FORCEPROP 1 LASTPIN (-3675 1825) $PN 2
J 0
(-3665 1805);
DISPLAY 0.489362 (-3665 1805);
PAINT MONO (-3665 1805);
FORCEPROP 1 LAST VALUE 0.22UF
J 0
(-3625 2000);
DISPLAY 0.489362 (-3625 2000);
PAINT SKYBLUE (-3625 2000);
FORCEPROP 1 LAST PACK_TYPE 0402
J 0
(-3625 1750);
DISPLAY 0.489362 (-3625 1750);
PAINT SKYBLUE (-3625 1750);
FORCEPROP 1 LAST MATERIAL X7R
J 0
(-3625 1850);
DISPLAY 0.489362 (-3625 1850);
PAINT SKYBLUE (-3625 1850);
FORCEPROP 1 LAST TOLERANCE 10%
J 0
(-3625 1900);
DISPLAY 0.489362 (-3625 1900);
PAINT SKYBLUE (-3625 1900);
FORCEPROP 1 LAST VOLTAGE 16V
J 0
(-3625 1950);
DISPLAY 0.489362 (-3625 1950);
PAINT SKYBLUE (-3625 1950);
FORCEPROP 2 LAST CDS_LIB pure_quanta
J 0
(-3675 1925);
DISPLAY INVISIBLE (-3675 1925);
FORCEPROP 1 LAST PATH I55
J 0
(-3625 2075);
DISPLAY 0.978723 (-3625 2075);
PAINT WHITE (-3625 2075);
DISPLAY INVISIBLE (-3625 2075);
FORCEPROP 1 LAST PART_NUMBER CH4223K1B00
J 0
(-3625 1800);
DISPLAY 0.489362 (-3625 1800);
PAINT SKYBLUE (-3625 1800);
DISPLAY INVISIBLE (-3625 1800);
FORCEADD Q_INDUCTOR4P_14..1
(-2875 1575);
FORCEPROP 1 LAST LOCATION PL29
J 0
(-3100 1830);
DISPLAY 0.489362 (-3100 1830);
PAINT SKYBLUE (-3100 1830);
FORCEPROP 0 LAST $SEC 1
J 0
(-3100 1975);
DISPLAY 0.680851 (-3100 1975);
PAINT MONO (-3100 1975);
DISPLAY INVISIBLE (-3100 1975);
FORCEPROP 0 LAST CDS_SEC 1
J 0
(-3100 1975);
DISPLAY 1.021277 (-3100 1975);
DISPLAY INVISIBLE (-3100 1975);
FORCEPROP 0 LASTPIN (-3275 1700) $PN 1
J 2
(-3285 1710);
DISPLAY 0.489362 (-3285 1710);
PAINT MONO (-3285 1710);
FORCEPROP 0 LASTPIN (-3275 1450) $PN 2
J 2
(-3285 1460);
DISPLAY 0.489362 (-3285 1460);
PAINT MONO (-3285 1460);
FORCEPROP 0 LASTPIN (-2475 1450) $PN 3
J 0
(-2465 1460);
DISPLAY 0.489362 (-2465 1460);
PAINT MONO (-2465 1460);
FORCEPROP 0 LASTPIN (-2475 1700) $PN 4
J 0
(-2465 1710);
DISPLAY 0.489362 (-2465 1710);
PAINT MONO (-2465 1710);
FORCEPROP 2 LAST PART_TYPE SMLF
J 0
(-3100 1925);
DISPLAY 1.021277 (-3100 1925);
FORCEPROP 1 LAST MATERIAL IND
J 0
(-3100 1785);
DISPLAY 0.489362 (-3100 1785);
PAINT SKYBLUE (-3100 1785);
FORCEPROP 2 LAST VALUE 150NH
J 0
(-3100 1875);
DISPLAY 0.489362 (-3100 1875);
PAINT SKYBLUE (-3100 1875);
FORCEPROP 2 LAST CDS_LIB pure_quanta
J 0
(-2875 1575);
DISPLAY INVISIBLE (-2875 1575);
FORCEPROP 1 LAST NEEDS_NO_SIZE TRUE
J 0
(-2875 1575);
DISPLAY 0.468085 (-2875 1575);
PAINT GREEN (-2875 1575);
DISPLAY INVISIBLE (-2875 1575);
FORCEPROP 1 LAST PATH I56
J 0
(-2675 1730);
DISPLAY 0.723404 (-2675 1730);
PAINT GREEN (-2675 1730);
DISPLAY INVISIBLE (-2675 1730);
FORCEPROP 1 LAST PART_NUMBER CV+15^0TZ04
J 0
(-3100 1735);
DISPLAY 0.489362 (-3100 1735);
PAINT SKYBLUE (-3100 1735);
DISPLAY INVISIBLE (-3100 1735);
FORCEADD OFFPAGE..3
(-2100 1450);
FORCEPROP 2 LAST $XR0 212 
J 0
(-1886 1450);
DISPLAY 0.638298 (-1886 1450);
PAINT MONO (-1886 1450);
FORCEPROP 2 LAST CDS_LIB standard
J 0
(-2100 1450);
DISPLAY INVISIBLE (-2100 1450);
FORCEPROP 1 LAST OFFPAGE TRUE
J 0
(-1775 1325);
DISPLAY 0.872340 (-1775 1325);
PAINT GREEN (-1775 1325);
DISPLAY INVISIBLE (-1775 1325);
FORCEPROP 1 LAST COMMENT_BODY TRUE
J 0
(-2150 1350);
DISPLAY 0.872340 (-2150 1350);
PAINT GREEN (-2150 1350);
DISPLAY INVISIBLE (-2150 1350);
FORCEPROP 2 LAST PATH I57
J 0
(-1875 1500);
DISPLAY 0.680851 (-1875 1500);
DISPLAY INVISIBLE (-1875 1500);
FORCEADD Q_CAPP..1
(-2750 2900);
FORCEPROP 1 LAST LOCATION PC275
J 0
(-2700 3000);
DISPLAY 0.489362 (-2700 3000);
PAINT SKYBLUE (-2700 3000);
FORCEPROP 0 LAST $SEC 1
J 0
(-2700 3025);
DISPLAY 0.680851 (-2700 3025);
PAINT MONO (-2700 3025);
DISPLAY INVISIBLE (-2700 3025);
FORCEPROP 0 LAST CDS_SEC 1
J 0
(-2700 3025);
DISPLAY 1.021277 (-2700 3025);
DISPLAY INVISIBLE (-2700 3025);
FORCEPROP 1 LASTPIN (-2750 3000) $PN 1
J 0
(-2740 2985);
DISPLAY 0.489362 (-2740 2985);
PAINT MONO (-2740 2985);
FORCEPROP 1 LASTPIN (-2750 2800) $PN 2
J 0
(-2740 2785);
DISPLAY 0.489362 (-2740 2785);
PAINT MONO (-2740 2785);
FORCEPROP 1 LAST VALUE 220UF
J 0
(-2700 2950);
DISPLAY 0.489362 (-2700 2950);
PAINT SKYBLUE (-2700 2950);
FORCEPROP 1 LAST VOLTAGE 4V
J 0
(-2700 2850);
DISPLAY 0.489362 (-2700 2850);
PAINT SKYBLUE (-2700 2850);
FORCEPROP 1 LAST MATERIAL SPCAP
J 0
(-2700 2800);
DISPLAY 0.489362 (-2700 2800);
PAINT SKYBLUE (-2700 2800);
FORCEPROP 1 LAST PACK_TYPE SMLF
J 0
(-2700 2750);
DISPLAY 0.489362 (-2700 2750);
PAINT SKYBLUE (-2700 2750);
FORCEPROP 1 LAST TOLERANCE 20%
J 0
(-2700 2900);
DISPLAY 0.489362 (-2700 2900);
PAINT SKYBLUE (-2700 2900);
FORCEPROP 2 LAST CDS_LIB pure_quanta
J 0
(-2750 2900);
DISPLAY INVISIBLE (-2750 2900);
FORCEPROP 1 LAST PATH I58
J 0
(-2700 3050);
DISPLAY 0.978723 (-2700 3050);
DISPLAY INVISIBLE (-2700 3050);
FORCEPROP 1 LAST PART_NUMBER CH122KM8801
J 0
(-2700 2700);
DISPLAY 0.489362 (-2700 2700);
PAINT SKYBLUE (-2700 2700);
DISPLAY INVISIBLE (-2700 2700);
FORCEADD Q_CAPP..1
(-2425 2900);
FORCEPROP 1 LAST LOCATION PC276
J 0
(-2375 3000);
DISPLAY 0.489362 (-2375 3000);
PAINT SKYBLUE (-2375 3000);
FORCEPROP 0 LAST $SEC 1
J 0
(-2375 3025);
DISPLAY 0.680851 (-2375 3025);
PAINT MONO (-2375 3025);
DISPLAY INVISIBLE (-2375 3025);
FORCEPROP 0 LAST CDS_SEC 1
J 0
(-2375 3025);
DISPLAY 1.021277 (-2375 3025);
DISPLAY INVISIBLE (-2375 3025);
FORCEPROP 1 LASTPIN (-2425 3000) $PN 1
J 0
(-2415 2985);
DISPLAY 0.489362 (-2415 2985);
PAINT MONO (-2415 2985);
FORCEPROP 1 LASTPIN (-2425 2800) $PN 2
J 0
(-2415 2785);
DISPLAY 0.489362 (-2415 2785);
PAINT MONO (-2415 2785);
FORCEPROP 1 LAST VALUE 220UF
J 0
(-2375 2950);
DISPLAY 0.489362 (-2375 2950);
PAINT SKYBLUE (-2375 2950);
FORCEPROP 1 LAST TOLERANCE 20%
J 0
(-2375 2900);
DISPLAY 0.489362 (-2375 2900);
PAINT SKYBLUE (-2375 2900);
FORCEPROP 1 LAST VOLTAGE 4V
J 0
(-2375 2850);
DISPLAY 0.489362 (-2375 2850);
PAINT SKYBLUE (-2375 2850);
FORCEPROP 1 LAST PACK_TYPE SMLF
J 0
(-2375 2750);
DISPLAY 0.489362 (-2375 2750);
PAINT SKYBLUE (-2375 2750);
FORCEPROP 1 LAST MATERIAL SPCAP
J 0
(-2375 2800);
DISPLAY 0.489362 (-2375 2800);
PAINT SKYBLUE (-2375 2800);
FORCEPROP 2 LAST CDS_LIB pure_quanta
J 0
(-2425 2900);
DISPLAY INVISIBLE (-2425 2900);
FORCEPROP 1 LAST PATH I59
J 0
(-2375 3050);
DISPLAY 0.978723 (-2375 3050);
DISPLAY INVISIBLE (-2375 3050);
FORCEPROP 1 LAST PART_NUMBER CH122KM8801
J 0
(-2375 2700);
DISPLAY 0.489362 (-2375 2700);
PAINT SKYBLUE (-2375 2700);
DISPLAY INVISIBLE (-2375 2700);
FORCEADD OFFPAGE..2
R 2
(-7225 1200);
FORCEPROP 2 LAST $XR3 210 
J 0
(-7720 1164);
DISPLAY 0.638298 (-7720 1164);
PAINT MONO (-7720 1164);
FORCEPROP 2 LAST $XR2 213 
J 0
(-7600 1164);
DISPLAY 0.638298 (-7600 1164);
PAINT MONO (-7600 1164);
FORCEPROP 2 LAST $XR1 212 
J 0
(-7480 1164);
DISPLAY 0.638298 (-7480 1164);
PAINT MONO (-7480 1164);
FORCEPROP 2 LAST $XR0 211 
J 0
(-7480 1200);
DISPLAY 0.638298 (-7480 1200);
PAINT MONO (-7480 1200);
FORCEPROP 2 LAST CDS_LIB standard
J 0
(-7225 1200);
DISPLAY INVISIBLE (-7225 1200);
FORCEPROP 1 LAST OFFPAGE TRUE
J 2
(-7550 1075);
DISPLAY 0.872340 (-7550 1075);
PAINT GREEN (-7550 1075);
DISPLAY INVISIBLE (-7550 1075);
FORCEPROP 1 LAST COMMENT_BODY TRUE
J 2
(-7180 1105);
DISPLAY 0.872340 (-7180 1105);
PAINT GREEN (-7180 1105);
DISPLAY INVISIBLE (-7180 1105);
FORCEPROP 2 LAST PATH I6
J 0
(-7475 1250);
DISPLAY 0.680851 (-7475 1250);
DISPLAY INVISIBLE (-7475 1250);
FORCEADD Q_CAPP..1
(-2100 2900);
FORCEPROP 1 LAST LOCATION PC277
J 0
(-2050 3000);
DISPLAY 0.489362 (-2050 3000);
PAINT SKYBLUE (-2050 3000);
FORCEPROP 0 LAST $SEC 1
J 0
(-2050 3025);
DISPLAY 0.680851 (-2050 3025);
PAINT MONO (-2050 3025);
DISPLAY INVISIBLE (-2050 3025);
FORCEPROP 0 LAST CDS_SEC 1
J 0
(-2050 3025);
DISPLAY 1.021277 (-2050 3025);
DISPLAY INVISIBLE (-2050 3025);
FORCEPROP 1 LASTPIN (-2100 3000) $PN 1
J 0
(-2090 2985);
DISPLAY 0.489362 (-2090 2985);
PAINT MONO (-2090 2985);
FORCEPROP 1 LASTPIN (-2100 2800) $PN 2
J 0
(-2090 2785);
DISPLAY 0.489362 (-2090 2785);
PAINT MONO (-2090 2785);
FORCEPROP 1 LAST VOLTAGE 4V
J 0
(-2050 2850);
DISPLAY 0.489362 (-2050 2850);
PAINT SKYBLUE (-2050 2850);
FORCEPROP 1 LAST MATERIAL SPCAP
J 0
(-2050 2800);
DISPLAY 0.489362 (-2050 2800);
PAINT SKYBLUE (-2050 2800);
FORCEPROP 1 LAST PACK_TYPE SMLF
J 0
(-2050 2750);
DISPLAY 0.489362 (-2050 2750);
PAINT SKYBLUE (-2050 2750);
FORCEPROP 1 LAST VALUE 220UF
J 0
(-2050 2950);
DISPLAY 0.489362 (-2050 2950);
PAINT SKYBLUE (-2050 2950);
FORCEPROP 1 LAST TOLERANCE 20%
J 0
(-2050 2900);
DISPLAY 0.489362 (-2050 2900);
PAINT SKYBLUE (-2050 2900);
FORCEPROP 2 LAST CDS_LIB pure_quanta
J 0
(-2100 2900);
DISPLAY INVISIBLE (-2100 2900);
FORCEPROP 1 LAST PATH I60
J 0
(-2050 3050);
DISPLAY 0.978723 (-2050 3050);
DISPLAY INVISIBLE (-2050 3050);
FORCEPROP 1 LAST PART_NUMBER CH122KM8801
J 0
(-2050 2700);
DISPLAY 0.489362 (-2050 2700);
PAINT SKYBLUE (-2050 2700);
DISPLAY INVISIBLE (-2050 2700);
FORCEADD Q_CAP..1
(-1700 1525);
FORCEPROP 1 LAST LOCATION PC280_2
J 0
(-1650 1625);
DISPLAY 0.489362 (-1650 1625);
PAINT SKYBLUE (-1650 1625);
FORCEPROP 0 LAST $SEC 1
J 0
(-1650 1650);
DISPLAY 0.680851 (-1650 1650);
PAINT MONO (-1650 1650);
DISPLAY INVISIBLE (-1650 1650);
FORCEPROP 0 LAST CDS_SEC 1
J 0
(-1650 1650);
DISPLAY 1.021277 (-1650 1650);
DISPLAY INVISIBLE (-1650 1650);
FORCEPROP 1 LASTPIN (-1700 1625) $PN 1
J 0
(-1690 1605);
DISPLAY 0.489362 (-1690 1605);
PAINT MONO (-1690 1605);
FORCEPROP 1 LASTPIN (-1700 1425) $PN 2
J 0
(-1690 1405);
DISPLAY 0.489362 (-1690 1405);
PAINT MONO (-1690 1405);
FORCEPROP 1 LAST VOLTAGE 4V
J 0
(-1650 1525);
DISPLAY 0.489362 (-1650 1525);
PAINT SKYBLUE (-1650 1525);
FORCEPROP 1 LAST VALUE 22UF
J 0
(-1650 1575);
DISPLAY 0.489362 (-1650 1575);
PAINT SKYBLUE (-1650 1575);
FORCEPROP 1 LAST TOLERANCE 20%
J 0
(-1650 1475);
DISPLAY 0.489362 (-1650 1475);
PAINT SKYBLUE (-1650 1475);
FORCEPROP 1 LAST MATERIAL X6S
J 0
(-1650 1425);
DISPLAY 0.489362 (-1650 1425);
PAINT SKYBLUE (-1650 1425);
FORCEPROP 1 LAST PACK_TYPE C0805
J 0
(-1650 1325);
DISPLAY 0.489362 (-1650 1325);
PAINT SKYBLUE (-1650 1325);
FORCEPROP 2 LAST CDS_LIB pure_quanta
J 0
(-1700 1525);
DISPLAY INVISIBLE (-1700 1525);
FORCEPROP 1 LAST PATH I61
J 0
(-1650 1675);
DISPLAY 0.978723 (-1650 1675);
PAINT WHITE (-1650 1675);
DISPLAY INVISIBLE (-1650 1675);
FORCEPROP 1 LAST PART_NUMBER CH622KMEA03
J 0
(-1650 1375);
DISPLAY 0.489362 (-1650 1375);
PAINT SKYBLUE (-1650 1375);
DISPLAY INVISIBLE (-1650 1375);
FORCEADD UNIVERSAL_GND..1
(-1275 1175);
FORCEPROP 3 LASTPIN (-1275 1225) SIG_NAME GND\g
J 0
(-1265 1235);
DISPLAY 0.659574 (-1265 1235);
PAINT MONO (-1265 1235);
DISPLAY INVISIBLE (-1265 1235);
FORCEPROP 2 LAST CDS_LIB pure_quanta_power
J 0
(-1275 1175);
DISPLAY INVISIBLE (-1275 1175);
FORCEPROP 1 LAST HDL_POWER GND
J 1
(-1250 1100);
DISPLAY 0.872340 (-1250 1100);
PAINT GREEN (-1250 1100);
DISPLAY INVISIBLE (-1250 1100);
FORCEPROP 1 LAST PATH I62
J 0
(-1200 1175);
DISPLAY 0.872340 (-1200 1175);
PAINT AQUA (-1200 1175);
DISPLAY INVISIBLE (-1200 1175);
FORCEADD Q_CAP..1
(-1275 1525);
FORCEPROP 1 LAST LOCATION PC282_2
J 0
(-1225 1625);
DISPLAY 0.489362 (-1225 1625);
PAINT SKYBLUE (-1225 1625);
FORCEPROP 0 LAST $SEC 1
J 0
(-1225 1650);
DISPLAY 0.680851 (-1225 1650);
PAINT MONO (-1225 1650);
DISPLAY INVISIBLE (-1225 1650);
FORCEPROP 0 LAST CDS_SEC 1
J 0
(-1225 1650);
DISPLAY 1.021277 (-1225 1650);
DISPLAY INVISIBLE (-1225 1650);
FORCEPROP 1 LASTPIN (-1275 1625) $PN 1
J 0
(-1265 1605);
DISPLAY 0.489362 (-1265 1605);
PAINT MONO (-1265 1605);
FORCEPROP 1 LASTPIN (-1275 1425) $PN 2
J 0
(-1265 1405);
DISPLAY 0.489362 (-1265 1405);
PAINT MONO (-1265 1405);
FORCEPROP 1 LAST VOLTAGE 4V
J 0
(-1225 1525);
DISPLAY 0.489362 (-1225 1525);
PAINT SKYBLUE (-1225 1525);
FORCEPROP 1 LAST VALUE 22UF
J 0
(-1225 1575);
DISPLAY 0.489362 (-1225 1575);
PAINT SKYBLUE (-1225 1575);
FORCEPROP 1 LAST TOLERANCE 20%
J 0
(-1225 1475);
DISPLAY 0.489362 (-1225 1475);
PAINT SKYBLUE (-1225 1475);
FORCEPROP 1 LAST MATERIAL X6S
J 0
(-1225 1425);
DISPLAY 0.489362 (-1225 1425);
PAINT SKYBLUE (-1225 1425);
FORCEPROP 1 LAST PACK_TYPE C0805
J 0
(-1225 1325);
DISPLAY 0.489362 (-1225 1325);
PAINT SKYBLUE (-1225 1325);
FORCEPROP 2 LAST CDS_LIB pure_quanta
J 0
(-1275 1525);
DISPLAY INVISIBLE (-1275 1525);
FORCEPROP 1 LAST PATH I63
J 0
(-1225 1675);
DISPLAY 0.978723 (-1225 1675);
PAINT WHITE (-1225 1675);
DISPLAY INVISIBLE (-1225 1675);
FORCEPROP 1 LAST PART_NUMBER CH622KMEA03
J 0
(-1225 1375);
DISPLAY 0.489362 (-1225 1375);
PAINT SKYBLUE (-1225 1375);
DISPLAY INVISIBLE (-1225 1375);
FORCEADD VCC_CORE..1
(-1275 1850);
FORCEPROP 3 LASTPIN (-1275 1800) SIG_NAME PVDDCR_CPU0_P1\g
J 0
(-1265 1810);
DISPLAY 0.659574 (-1265 1810);
PAINT MONO (-1265 1810);
DISPLAY INVISIBLE (-1265 1810);
FORCEPROP 1 LAST HDL_POWER PVDDCR_CPU0_P1
J 1
(-1275 1900);
DISPLAY 0.489362 (-1275 1900);
PAINT GREEN (-1275 1900);
FORCEPROP 2 LAST CDS_LIB pure_quanta_power
J 0
(-1275 1850);
DISPLAY INVISIBLE (-1275 1850);
FORCEPROP 1 LAST PATH I64
J 0
(-1225 1875);
DISPLAY 0.872340 (-1225 1875);
PAINT AQUA (-1225 1875);
DISPLAY INVISIBLE (-1225 1875);
FORCEADD UNIVERSAL_GND..1
(-1800 2525);
FORCEPROP 3 LASTPIN (-1800 2575) SIG_NAME GND\g
J 0
(-1790 2585);
DISPLAY 0.659574 (-1790 2585);
PAINT MONO (-1790 2585);
DISPLAY INVISIBLE (-1790 2585);
FORCEPROP 2 LAST CDS_LIB pure_quanta_power
J 0
(-1800 2525);
DISPLAY INVISIBLE (-1800 2525);
FORCEPROP 1 LAST HDL_POWER GND
J 1
(-1775 2450);
DISPLAY 0.872340 (-1775 2450);
PAINT GREEN (-1775 2450);
DISPLAY INVISIBLE (-1775 2450);
FORCEPROP 1 LAST PATH I65
J 0
(-1725 2525);
DISPLAY 0.872340 (-1725 2525);
PAINT AQUA (-1725 2525);
DISPLAY INVISIBLE (-1725 2525);
FORCEADD Q_CAPP..1
(-1800 2900);
FORCEPROP 1 LAST LOCATION PC279
J 0
(-1750 3000);
DISPLAY 0.489362 (-1750 3000);
PAINT SKYBLUE (-1750 3000);
FORCEPROP 0 LAST $SEC 1
J 0
(-1750 3050);
DISPLAY 0.680851 (-1750 3050);
PAINT MONO (-1750 3050);
DISPLAY INVISIBLE (-1750 3050);
FORCEPROP 0 LAST CDS_SEC 1
J 0
(-1750 3050);
DISPLAY 1.021277 (-1750 3050);
DISPLAY INVISIBLE (-1750 3050);
FORCEPROP 1 LASTPIN (-1800 3000) $PN 1
J 0
(-1790 2985);
DISPLAY 0.489362 (-1790 2985);
PAINT MONO (-1790 2985);
FORCEPROP 1 LASTPIN (-1800 2800) $PN 2
J 0
(-1790 2785);
DISPLAY 0.489362 (-1790 2785);
PAINT MONO (-1790 2785);
FORCEPROP 1 LAST VALUE 220UF
J 0
(-1750 2950);
DISPLAY 0.489362 (-1750 2950);
PAINT SKYBLUE (-1750 2950);
FORCEPROP 1 LAST TOLERANCE 20%
J 0
(-1750 2900);
DISPLAY 0.489362 (-1750 2900);
PAINT SKYBLUE (-1750 2900);
FORCEPROP 1 LAST VOLTAGE 4V
J 0
(-1750 2850);
DISPLAY 0.489362 (-1750 2850);
PAINT SKYBLUE (-1750 2850);
FORCEPROP 1 LAST PACK_TYPE SMLF
J 0
(-1750 2750);
DISPLAY 0.489362 (-1750 2750);
PAINT SKYBLUE (-1750 2750);
FORCEPROP 1 LAST MATERIAL SPCAP
J 0
(-1750 2800);
DISPLAY 0.489362 (-1750 2800);
PAINT SKYBLUE (-1750 2800);
FORCEPROP 2 LAST CDS_LIB pure_quanta
J 0
(-1800 2900);
DISPLAY INVISIBLE (-1800 2900);
FORCEPROP 1 LAST PATH I66
J 0
(-1750 3050);
DISPLAY 0.978723 (-1750 3050);
DISPLAY INVISIBLE (-1750 3050);
FORCEPROP 1 LAST PART_NUMBER CH122KM8801
J 0
(-1750 2700);
DISPLAY 0.489362 (-1750 2700);
PAINT SKYBLUE (-1750 2700);
DISPLAY INVISIBLE (-1750 2700);
FORCEADD VCC_CORE..1
(-1800 3200);
FORCEPROP 3 LASTPIN (-1800 3150) SIG_NAME PVDDCR_CPU0_P1\g
J 0
(-1790 3160);
DISPLAY 0.659574 (-1790 3160);
PAINT MONO (-1790 3160);
DISPLAY INVISIBLE (-1790 3160);
FORCEPROP 1 LAST HDL_POWER PVDDCR_CPU0_P1
J 1
(-1800 3250);
DISPLAY 0.489362 (-1800 3250);
PAINT GREEN (-1800 3250);
FORCEPROP 2 LAST CDS_LIB pure_quanta_power
J 0
(-1800 3200);
DISPLAY INVISIBLE (-1800 3200);
FORCEPROP 1 LAST PATH I67
J 0
(-1750 3225);
DISPLAY 0.872340 (-1750 3225);
PAINT AQUA (-1750 3225);
DISPLAY INVISIBLE (-1750 3225);
FORCEADD UNIVERSAL_GND..1
(-925 3925);
FORCEPROP 3 LASTPIN (-925 3975) SIG_NAME GND\g
J 0
(-915 3985);
DISPLAY 0.659574 (-915 3985);
PAINT MONO (-915 3985);
DISPLAY INVISIBLE (-915 3985);
FORCEPROP 2 LAST CDS_LIB pure_quanta_power
J 0
(-925 3925);
DISPLAY INVISIBLE (-925 3925);
FORCEPROP 1 LAST HDL_POWER GND
J 1
(-900 3850);
DISPLAY 0.872340 (-900 3850);
PAINT GREEN (-900 3850);
DISPLAY INVISIBLE (-900 3850);
FORCEPROP 1 LAST PATH I68
J 0
(-850 3925);
DISPLAY 0.872340 (-850 3925);
PAINT AQUA (-850 3925);
DISPLAY INVISIBLE (-850 3925);
FORCEADD UNIVERSAL_GND..1
(-4000 4975);
FORCEPROP 3 LASTPIN (-4000 5025) SIG_NAME GND\g
J 0
(-3990 5035);
DISPLAY 0.659574 (-3990 5035);
PAINT MONO (-3990 5035);
DISPLAY INVISIBLE (-3990 5035);
FORCEPROP 2 LAST CDS_LIB pure_quanta_power
J 0
(-4000 4975);
DISPLAY INVISIBLE (-4000 4975);
FORCEPROP 1 LAST HDL_POWER GND
J 1
(-3975 4900);
DISPLAY 0.872340 (-3975 4900);
PAINT GREEN (-3975 4900);
DISPLAY INVISIBLE (-3975 4900);
FORCEPROP 1 LAST PATH I69
J 0
(-3925 4975);
DISPLAY 0.872340 (-3925 4975);
PAINT AQUA (-3925 4975);
DISPLAY INVISIBLE (-3925 4975);
FORCEADD OFFPAGE..1
(-7200 1100);
FORCEPROP 2 LAST $XR0 210 
J 0
(-7452 1100);
DISPLAY 0.638298 (-7452 1100);
PAINT MONO (-7452 1100);
FORCEPROP 2 LAST CDS_LIB standard
J 2
(-7200 1100);
DISPLAY INVISIBLE (-7200 1100);
FORCEPROP 1 LAST OFFPAGE TRUE
J 0
(-6875 975);
DISPLAY 0.872340 (-6875 975);
PAINT GREEN (-6875 975);
DISPLAY INVISIBLE (-6875 975);
FORCEPROP 1 LAST COMMENT_BODY TRUE
J 0
(-7075 1000);
DISPLAY 0.872340 (-7075 1000);
PAINT GREEN (-7075 1000);
DISPLAY INVISIBLE (-7075 1000);
FORCEPROP 2 LAST PATH I7
J 0
(-7450 1150);
DISPLAY 0.680851 (-7450 1150);
DISPLAY INVISIBLE (-7450 1150);
FORCEADD Q_CAPP..1
(-3850 5325);
FORCEPROP 1 LAST LOCATION PC272
J 0
(-3800 5425);
DISPLAY 0.489362 (-3800 5425);
PAINT SKYBLUE (-3800 5425);
FORCEPROP 0 LAST $SEC 1
J 0
(-3800 5450);
DISPLAY 0.680851 (-3800 5450);
PAINT MONO (-3800 5450);
DISPLAY INVISIBLE (-3800 5450);
FORCEPROP 0 LAST CDS_SEC 1
J 0
(-3800 5450);
DISPLAY 1.021277 (-3800 5450);
DISPLAY INVISIBLE (-3800 5450);
FORCEPROP 1 LASTPIN (-3850 5425) $PN 1
J 0
(-3840 5410);
DISPLAY 0.489362 (-3840 5410);
PAINT MONO (-3840 5410);
FORCEPROP 1 LASTPIN (-3850 5225) $PN 2
J 0
(-3840 5210);
DISPLAY 0.489362 (-3840 5210);
PAINT MONO (-3840 5210);
FORCEPROP 1 LAST MATERIAL OSCON
J 0
(-3800 5225);
DISPLAY 0.489362 (-3800 5225);
PAINT SKYBLUE (-3800 5225);
FORCEPROP 1 LAST VOLTAGE 16V
J 0
(-3800 5275);
DISPLAY 0.489362 (-3800 5275);
PAINT SKYBLUE (-3800 5275);
FORCEPROP 1 LAST PACK_TYPE THLF
J 0
(-3800 5175);
DISPLAY 0.489362 (-3800 5175);
PAINT SKYBLUE (-3800 5175);
FORCEPROP 1 LAST TOLERANCE 20%
J 0
(-3800 5325);
DISPLAY 0.489362 (-3800 5325);
PAINT SKYBLUE (-3800 5325);
FORCEPROP 1 LAST VALUE 270UF
J 0
(-3800 5375);
DISPLAY 0.489362 (-3800 5375);
PAINT SKYBLUE (-3800 5375);
FORCEPROP 2 LAST CDS_LIB pure_quanta
J 0
(-3850 5325);
DISPLAY INVISIBLE (-3850 5325);
FORCEPROP 1 LAST PATH I70
J 0
(-3800 5475);
DISPLAY 0.978723 (-3800 5475);
DISPLAY INVISIBLE (-3800 5475);
FORCEPROP 1 LAST PART_NUMBER CC72703MD38
J 0
(-3800 5125);
DISPLAY 0.489362 (-3800 5125);
PAINT SKYBLUE (-3800 5125);
DISPLAY INVISIBLE (-3800 5125);
FORCEADD Q_CAPP..1
(-3475 5325);
FORCEPROP 1 LAST LOCATION PC273
J 0
(-3425 5425);
DISPLAY 0.489362 (-3425 5425);
PAINT SKYBLUE (-3425 5425);
FORCEPROP 0 LAST $SEC 1
J 0
(-3425 5450);
DISPLAY 0.680851 (-3425 5450);
PAINT MONO (-3425 5450);
DISPLAY INVISIBLE (-3425 5450);
FORCEPROP 0 LAST CDS_SEC 1
J 0
(-3425 5450);
DISPLAY 1.021277 (-3425 5450);
DISPLAY INVISIBLE (-3425 5450);
FORCEPROP 1 LASTPIN (-3475 5425) $PN 1
J 0
(-3465 5410);
DISPLAY 0.489362 (-3465 5410);
PAINT MONO (-3465 5410);
FORCEPROP 1 LASTPIN (-3475 5225) $PN 2
J 0
(-3465 5210);
DISPLAY 0.489362 (-3465 5210);
PAINT MONO (-3465 5210);
FORCEPROP 1 LAST VALUE 270UF
J 0
(-3425 5375);
DISPLAY 0.489362 (-3425 5375);
PAINT SKYBLUE (-3425 5375);
FORCEPROP 1 LAST TOLERANCE 20%
J 0
(-3425 5325);
DISPLAY 0.489362 (-3425 5325);
PAINT SKYBLUE (-3425 5325);
FORCEPROP 1 LAST PACK_TYPE THLF
J 0
(-3425 5175);
DISPLAY 0.489362 (-3425 5175);
PAINT SKYBLUE (-3425 5175);
FORCEPROP 1 LAST VOLTAGE 16V
J 0
(-3425 5275);
DISPLAY 0.489362 (-3425 5275);
PAINT SKYBLUE (-3425 5275);
FORCEPROP 1 LAST MATERIAL OSCON
J 0
(-3425 5225);
DISPLAY 0.489362 (-3425 5225);
PAINT SKYBLUE (-3425 5225);
FORCEPROP 2 LAST CDS_LIB pure_quanta
J 0
(-3475 5325);
DISPLAY INVISIBLE (-3475 5325);
FORCEPROP 1 LAST PATH I71
J 0
(-3425 5475);
DISPLAY 0.978723 (-3425 5475);
DISPLAY INVISIBLE (-3425 5475);
FORCEPROP 1 LAST PART_NUMBER CC72703MD38
J 0
(-3425 5125);
DISPLAY 0.489362 (-3425 5125);
PAINT SKYBLUE (-3425 5125);
DISPLAY INVISIBLE (-3425 5125);
FORCEADD OFFPAGE..3
(-2375 4200);
FORCEPROP 2 LAST $XR0 211 
J 0
(-2131 4200);
DISPLAY 0.638298 (-2131 4200);
PAINT MONO (-2131 4200);
FORCEPROP 2 LAST CDS_LIB standard
J 2
(-2375 4200);
DISPLAY INVISIBLE (-2375 4200);
FORCEPROP 1 LAST OFFPAGE TRUE
J 0
(-2050 4075);
DISPLAY 0.872340 (-2050 4075);
PAINT GREEN (-2050 4075);
DISPLAY INVISIBLE (-2050 4075);
FORCEPROP 1 LAST COMMENT_BODY TRUE
J 0
(-2425 4100);
DISPLAY 0.872340 (-2425 4100);
PAINT GREEN (-2425 4100);
DISPLAY INVISIBLE (-2425 4100);
FORCEPROP 2 LAST PATH I72
J 0
(-2125 4250);
DISPLAY 0.680851 (-2125 4250);
DISPLAY INVISIBLE (-2125 4250);
FORCEADD Q_INDUCTOR..1
(-2900 5525);
FORCEPROP 1 LAST LOCATION PL30
J 0
(-3025 5685);
DISPLAY 0.489362 (-3025 5685);
PAINT SKYBLUE (-3025 5685);
FORCEPROP 0 LAST $SEC 1
J 0
(-3025 5800);
DISPLAY 0.680851 (-3025 5800);
PAINT MONO (-3025 5800);
DISPLAY INVISIBLE (-3025 5800);
FORCEPROP 0 LAST CDS_SEC 1
J 0
(-3025 5800);
DISPLAY 1.021277 (-3025 5800);
DISPLAY INVISIBLE (-3025 5800);
FORCEPROP 0 LASTPIN (-3000 5500) $PN 1
J 2
(-3010 5510);
DISPLAY 0.489362 (-3010 5510);
PAINT MONO (-3010 5510);
FORCEPROP 0 LASTPIN (-2800 5500) $PN 2
J 0
(-2790 5510);
DISPLAY 0.489362 (-2790 5510);
PAINT MONO (-2790 5510);
FORCEPROP 2 LAST VALUE 50NH/86A
J 0
(-3025 5775);
DISPLAY 0.489362 (-3025 5775);
PAINT SKYBLUE (-3025 5775);
FORCEPROP 1 LAST MATERIAL IND
J 0
(-3025 5580);
DISPLAY 0.489362 (-3025 5580);
PAINT SKYBLUE (-3025 5580);
FORCEPROP 2 LAST PACK_TYPE SMLF
J 0
(-3025 5725);
DISPLAY 0.489362 (-3025 5725);
PAINT SKYBLUE (-3025 5725);
FORCEPROP 2 LAST CDS_LIB pure_quanta
J 0
(-2900 5525);
DISPLAY INVISIBLE (-2900 5525);
FORCEPROP 1 LAST NEEDS_NO_SIZE TRUE
J 0
(-2900 5525);
DISPLAY 0.468085 (-2900 5525);
PAINT GREEN (-2900 5525);
DISPLAY INVISIBLE (-2900 5525);
FORCEPROP 1 LAST PATH I73
J 0
(-2825 5580);
DISPLAY 0.723404 (-2825 5580);
PAINT GREEN (-2825 5580);
DISPLAY INVISIBLE (-2825 5580);
FORCEPROP 1 LAST PART_NUMBER CVA50^0MZ09
J 0
(-3025 5635);
DISPLAY 0.489362 (-3025 5635);
PAINT SKYBLUE (-3025 5635);
DISPLAY INVISIBLE (-3025 5635);
FORCEADD Q_CAP..1
(-2550 5350);
FORCEPROP 1 LAST LOCATION PC6004
J 0
(-2500 5450);
DISPLAY 0.489362 (-2500 5450);
PAINT SKYBLUE (-2500 5450);
FORCEPROP 0 LAST $SEC 1
J 0
(-2500 5475);
DISPLAY 0.680851 (-2500 5475);
PAINT MONO (-2500 5475);
DISPLAY INVISIBLE (-2500 5475);
FORCEPROP 0 LAST CDS_SEC 1
J 0
(-2500 5475);
DISPLAY 0.680851 (-2500 5475);
DISPLAY INVISIBLE (-2500 5475);
FORCEPROP 1 LASTPIN (-2550 5450) $PN 1
J 0
(-2540 5430);
DISPLAY 0.787234 (-2540 5430);
PAINT MONO (-2540 5430);
FORCEPROP 1 LASTPIN (-2550 5250) $PN 2
J 0
(-2540 5230);
DISPLAY 0.787234 (-2540 5230);
PAINT MONO (-2540 5230);
FORCEPROP 1 LAST PACK_TYPE 0402
J 0
(-2500 5150);
DISPLAY 0.489362 (-2500 5150);
PAINT SKYBLUE (-2500 5150);
FORCEPROP 1 LAST VOLTAGE 25V
J 0
(-2500 5350);
DISPLAY 0.489362 (-2500 5350);
PAINT SKYBLUE (-2500 5350);
FORCEPROP 1 LAST VALUE 0.1UF
J 0
(-2500 5400);
DISPLAY 0.489362 (-2500 5400);
PAINT SKYBLUE (-2500 5400);
FORCEPROP 1 LAST MATERIAL X7R
J 0
(-2500 5250);
DISPLAY 0.489362 (-2500 5250);
PAINT SKYBLUE (-2500 5250);
FORCEPROP 1 LAST TOLERANCE 10%
J 0
(-2500 5300);
DISPLAY 0.489362 (-2500 5300);
PAINT SKYBLUE (-2500 5300);
FORCEPROP 2 LAST CDS_LIB pure_quanta
J 0
(-2550 5350);
DISPLAY INVISIBLE (-2550 5350);
FORCEPROP 1 LAST PATH I74
J 0
(-2500 5500);
DISPLAY 0.978723 (-2500 5500);
PAINT WHITE (-2500 5500);
DISPLAY INVISIBLE (-2500 5500);
FORCEPROP 1 LAST PART_NUMBER CH4104K1B00
J 0
(-2500 5200);
DISPLAY 0.489362 (-2500 5200);
PAINT SKYBLUE (-2500 5200);
DISPLAY INVISIBLE (-2500 5200);
FORCEADD VCC_CORE..1
(-2550 5675);
FORCEPROP 3 LASTPIN (-2550 5625) SIG_NAME P12V_AUX\g
J 0
(-2540 5635);
DISPLAY 0.659574 (-2540 5635);
PAINT MONO (-2540 5635);
DISPLAY INVISIBLE (-2540 5635);
FORCEPROP 1 LAST HDL_POWER P12V_AUX
J 1
(-2550 5725);
DISPLAY 0.489362 (-2550 5725);
PAINT GREEN (-2550 5725);
FORCEPROP 2 LAST CDS_LIB pure_quanta_power
J 0
(-2550 5675);
DISPLAY INVISIBLE (-2550 5675);
FORCEPROP 1 LAST PATH I75
J 0
(-2500 5700);
DISPLAY 0.872340 (-2500 5700);
PAINT AQUA (-2500 5700);
DISPLAY INVISIBLE (-2500 5700);
FORCEADD Q_CAP..1
(-1650 4275);
FORCEPROP 1 LAST LOCATION PC281_1
J 0
(-1600 4375);
DISPLAY 0.489362 (-1600 4375);
PAINT SKYBLUE (-1600 4375);
FORCEPROP 0 LAST $SEC 1
J 0
(-1600 4400);
DISPLAY 0.680851 (-1600 4400);
PAINT MONO (-1600 4400);
DISPLAY INVISIBLE (-1600 4400);
FORCEPROP 0 LAST CDS_SEC 1
J 0
(-1600 4400);
DISPLAY 1.021277 (-1600 4400);
DISPLAY INVISIBLE (-1600 4400);
FORCEPROP 1 LASTPIN (-1650 4375) $PN 1
J 0
(-1640 4355);
DISPLAY 0.489362 (-1640 4355);
PAINT MONO (-1640 4355);
FORCEPROP 1 LASTPIN (-1650 4175) $PN 2
J 0
(-1640 4155);
DISPLAY 0.489362 (-1640 4155);
PAINT MONO (-1640 4155);
FORCEPROP 1 LAST VOLTAGE 4V
J 0
(-1600 4275);
DISPLAY 0.489362 (-1600 4275);
PAINT SKYBLUE (-1600 4275);
FORCEPROP 1 LAST VALUE 22UF
J 0
(-1600 4325);
DISPLAY 0.489362 (-1600 4325);
PAINT SKYBLUE (-1600 4325);
FORCEPROP 1 LAST MATERIAL X6S
J 0
(-1600 4175);
DISPLAY 0.489362 (-1600 4175);
PAINT SKYBLUE (-1600 4175);
FORCEPROP 1 LAST PACK_TYPE C0805
J 0
(-1600 4075);
DISPLAY 0.489362 (-1600 4075);
PAINT SKYBLUE (-1600 4075);
FORCEPROP 1 LAST TOLERANCE 20%
J 0
(-1600 4225);
DISPLAY 0.489362 (-1600 4225);
PAINT SKYBLUE (-1600 4225);
FORCEPROP 2 LAST CDS_LIB pure_quanta
J 0
(-1650 4275);
DISPLAY INVISIBLE (-1650 4275);
FORCEPROP 1 LAST PATH I76
J 0
(-1600 4425);
DISPLAY 0.978723 (-1600 4425);
PAINT WHITE (-1600 4425);
DISPLAY INVISIBLE (-1600 4425);
FORCEPROP 1 LAST PART_NUMBER CH622KMEA03
J 0
(-1600 4125);
DISPLAY 0.489362 (-1600 4125);
PAINT SKYBLUE (-1600 4125);
DISPLAY INVISIBLE (-1600 4125);
FORCEADD Q_CAP..1
(-1225 4275);
FORCEPROP 1 LAST LOCATION PC283_1
J 0
(-1175 4375);
DISPLAY 0.489362 (-1175 4375);
PAINT SKYBLUE (-1175 4375);
FORCEPROP 0 LAST $SEC 1
J 0
(-1175 4400);
DISPLAY 0.680851 (-1175 4400);
PAINT MONO (-1175 4400);
DISPLAY INVISIBLE (-1175 4400);
FORCEPROP 0 LAST CDS_SEC 1
J 0
(-1175 4400);
DISPLAY 1.021277 (-1175 4400);
DISPLAY INVISIBLE (-1175 4400);
FORCEPROP 1 LASTPIN (-1225 4375) $PN 1
J 0
(-1215 4355);
DISPLAY 0.489362 (-1215 4355);
PAINT MONO (-1215 4355);
FORCEPROP 1 LASTPIN (-1225 4175) $PN 2
J 0
(-1215 4155);
DISPLAY 0.489362 (-1215 4155);
PAINT MONO (-1215 4155);
FORCEPROP 1 LAST TOLERANCE 20%
J 0
(-1175 4225);
DISPLAY 0.489362 (-1175 4225);
PAINT SKYBLUE (-1175 4225);
FORCEPROP 1 LAST MATERIAL X6S
J 0
(-1175 4175);
DISPLAY 0.489362 (-1175 4175);
PAINT SKYBLUE (-1175 4175);
FORCEPROP 1 LAST VALUE 22UF
J 0
(-1175 4325);
DISPLAY 0.489362 (-1175 4325);
PAINT SKYBLUE (-1175 4325);
FORCEPROP 1 LAST VOLTAGE 4V
J 0
(-1175 4275);
DISPLAY 0.489362 (-1175 4275);
PAINT SKYBLUE (-1175 4275);
FORCEPROP 1 LAST PACK_TYPE C0805
J 0
(-1175 4125);
DISPLAY 0.489362 (-1175 4125);
PAINT SKYBLUE (-1175 4125);
FORCEPROP 2 LAST CDS_LIB pure_quanta
J 0
(-1225 4275);
DISPLAY INVISIBLE (-1225 4275);
FORCEPROP 1 LAST PATH I77
J 0
(-1175 4425);
DISPLAY 0.978723 (-1175 4425);
PAINT WHITE (-1175 4425);
DISPLAY INVISIBLE (-1175 4425);
FORCEPROP 1 LAST PART_NUMBER CH622KMEA03
J 0
(-1175 4125);
DISPLAY 0.489362 (-1175 4125);
PAINT SKYBLUE (-1175 4125);
DISPLAY INVISIBLE (-1175 4125);
FORCEADD Q_RES..2
(-925 4275);
FORCEPROP 1 LAST LOCATION PR337
J 0
(-880 4400);
DISPLAY 0.489362 (-880 4400);
PAINT SKYBLUE (-880 4400);
FORCEPROP 0 LAST $SEC 1
J 0
(-875 4425);
DISPLAY 0.680851 (-875 4425);
PAINT MONO (-875 4425);
DISPLAY INVISIBLE (-875 4425);
FORCEPROP 0 LAST CDS_SEC 1
J 0
(-875 4425);
DISPLAY 1.021277 (-875 4425);
DISPLAY INVISIBLE (-875 4425);
FORCEPROP 1 LASTPIN (-925 4375) $PN 1
J 0
(-920 4337);
DISPLAY 0.787234 (-920 4337);
PAINT MONO (-920 4337);
DISPLAY INVISIBLE (-920 4337);
FORCEPROP 1 LASTPIN (-925 4175) $PN 2
J 0
(-920 4185);
DISPLAY 0.787234 (-920 4185);
PAINT MONO (-920 4185);
DISPLAY INVISIBLE (-920 4185);
FORCEPROP 1 LAST PACK_TYPE 0402LF
J 0
(-885 4100);
DISPLAY 0.489362 (-885 4100);
PAINT SKYBLUE (-885 4100);
FORCEPROP 1 LAST VALUE 1K
J 0
(-880 4350);
DISPLAY 0.489362 (-880 4350);
PAINT SKYBLUE (-880 4350);
FORCEPROP 1 LAST TOLERANCE 1%
J 0
(-880 4300);
DISPLAY 0.489362 (-880 4300);
PAINT SKYBLUE (-880 4300);
FORCEPROP 1 LAST MATERIAL CHIP
J 0
(-885 4200);
DISPLAY 0.489362 (-885 4200);
PAINT SKYBLUE (-885 4200);
FORCEPROP 1 LAST WATTAGE 1/16W
J 0
(-885 4250);
DISPLAY 0.489362 (-885 4250);
PAINT SKYBLUE (-885 4250);
FORCEPROP 2 LAST CDS_LIB pure_quanta
J 0
(-925 4275);
DISPLAY INVISIBLE (-925 4275);
FORCEPROP 1 LAST PATH I78
J 0
(-875 4450);
DISPLAY 0.978723 (-875 4450);
PAINT WHITE (-875 4450);
DISPLAY INVISIBLE (-875 4450);
FORCEPROP 1 LAST PART_NUMBER CS21002FB06
J 0
(-885 4150);
DISPLAY 0.489362 (-885 4150);
PAINT SKYBLUE (-885 4150);
DISPLAY INVISIBLE (-885 4150);
FORCEADD VCC_CORE..1
(-925 4600);
FORCEPROP 3 LASTPIN (-925 4550) SIG_NAME PVDDCR_CPU0_P1\g
J 0
(-915 4560);
DISPLAY 0.659574 (-915 4560);
PAINT MONO (-915 4560);
DISPLAY INVISIBLE (-915 4560);
FORCEPROP 1 LAST HDL_POWER PVDDCR_CPU0_P1
J 1
(-925 4650);
DISPLAY 0.489362 (-925 4650);
PAINT GREEN (-925 4650);
FORCEPROP 2 LAST CDS_LIB pure_quanta_power
J 0
(-925 4600);
DISPLAY INVISIBLE (-925 4600);
FORCEPROP 1 LAST PATH I79
J 0
(-875 4625);
DISPLAY 0.872340 (-875 4625);
PAINT AQUA (-875 4625);
DISPLAY INVISIBLE (-875 4625);
FORCEADD OFFPAGE..2
R 2
(-7250 1700);
FORCEPROP 2 LAST $XR0 210 
J 0
(-7505 1700);
DISPLAY 0.638298 (-7505 1700);
PAINT MONO (-7505 1700);
FORCEPROP 2 LAST CDS_LIB standard
J 2
(-7250 1700);
DISPLAY INVISIBLE (-7250 1700);
FORCEPROP 1 LAST OFFPAGE TRUE
J 2
(-7575 1575);
DISPLAY 0.872340 (-7575 1575);
PAINT GREEN (-7575 1575);
DISPLAY INVISIBLE (-7575 1575);
FORCEPROP 1 LAST COMMENT_BODY TRUE
J 2
(-7205 1605);
DISPLAY 0.872340 (-7205 1605);
PAINT GREEN (-7205 1605);
DISPLAY INVISIBLE (-7205 1605);
FORCEPROP 2 LAST PATH I8
J 0
(-7525 1750);
DISPLAY 0.680851 (-7525 1750);
DISPLAY INVISIBLE (-7525 1750);
FORCEADD Q_RES..1
(-7275 1400);
FORCEPROP 1 LAST LOCATION PR188
J 0
(-7325 1450);
DISPLAY 0.489362 (-7325 1450);
PAINT SKYBLUE (-7325 1450);
FORCEPROP 0 LAST $SEC 1
J 0
(-7275 1475);
DISPLAY 0.680851 (-7275 1475);
PAINT MONO (-7275 1475);
DISPLAY INVISIBLE (-7275 1475);
FORCEPROP 0 LAST CDS_SEC 1
J 0
(-7275 1475);
DISPLAY 1.021277 (-7275 1475);
DISPLAY INVISIBLE (-7275 1475);
FORCEPROP 1 LASTPIN (-7375 1400) $PN 1
J 0
(-7363 1412);
DISPLAY 0.489362 (-7363 1412);
PAINT MONO (-7363 1412);
FORCEPROP 1 LASTPIN (-7175 1400) $PN 2
J 0
(-7213 1412);
DISPLAY 0.489362 (-7213 1412);
PAINT MONO (-7213 1412);
FORCEPROP 1 LAST WATTAGE 1/16W
J 0
(-7175 1300);
DISPLAY 0.489362 (-7175 1300);
PAINT SKYBLUE (-7175 1300);
FORCEPROP 1 LAST MATERIAL EMPTY
J 0
(-7575 1300);
DISPLAY 0.489362 (-7575 1300);
PAINT RED (-7575 1300);
FORCEPROP 1 LAST TOLERANCE 1%
J 0
(-7150 1425);
DISPLAY 0.489362 (-7150 1425);
PAINT SKYBLUE (-7150 1425);
FORCEPROP 1 LAST VALUE 8.87K
J 2
(-7375 1425);
DISPLAY 0.489362 (-7375 1425);
PAINT SKYBLUE (-7375 1425);
FORCEPROP 1 LAST PACK_TYPE 0402LF
J 0
(-7175 1350);
DISPLAY 0.489362 (-7175 1350);
PAINT SKYBLUE (-7175 1350);
FORCEPROP 2 LAST CDS_LIB pure_quanta
J 0
(-7275 1400);
DISPLAY INVISIBLE (-7275 1400);
FORCEPROP 1 LAST PATH I80
J 0
(-7325 1550);
DISPLAY 0.978723 (-7325 1550);
PAINT WHITE (-7325 1550);
DISPLAY INVISIBLE (-7325 1550);
FORCEPROP 1 LAST PART_NUMBER CS28872FB01
J 0
(-7575 1350);
DISPLAY 0.489362 (-7575 1350);
PAINT SKYBLUE (-7575 1350);
DISPLAY INVISIBLE (-7575 1350);
FORCEADD UNIVERSAL_GND..1
(-7925 1150);
FORCEPROP 3 LASTPIN (-7925 1200) SIG_NAME GND\g
J 0
(-7915 1210);
DISPLAY 0.659574 (-7915 1210);
PAINT MONO (-7915 1210);
DISPLAY INVISIBLE (-7915 1210);
FORCEPROP 2 LAST CDS_LIB pure_quanta_power
J 0
(-7925 1150);
DISPLAY INVISIBLE (-7925 1150);
FORCEPROP 1 LAST HDL_POWER GND
J 1
(-7900 1075);
DISPLAY 0.872340 (-7900 1075);
PAINT GREEN (-7900 1075);
DISPLAY INVISIBLE (-7900 1075);
FORCEPROP 1 LAST PATH I81
J 0
(-7850 1150);
DISPLAY 0.872340 (-7850 1150);
PAINT AQUA (-7850 1150);
DISPLAY INVISIBLE (-7850 1150);
FORCEADD UNIVERSAL_GND..1
(-7600 1225);
FORCEPROP 3 LASTPIN (-7600 1275) SIG_NAME GND\g
J 0
(-7590 1285);
DISPLAY 0.659574 (-7590 1285);
PAINT MONO (-7590 1285);
DISPLAY INVISIBLE (-7590 1285);
FORCEPROP 2 LAST CDS_LIB pure_quanta_power
J 0
(-7600 1225);
DISPLAY INVISIBLE (-7600 1225);
FORCEPROP 1 LAST HDL_POWER GND
J 1
(-7575 1150);
DISPLAY 0.872340 (-7575 1150);
PAINT GREEN (-7575 1150);
DISPLAY INVISIBLE (-7575 1150);
FORCEPROP 1 LAST PATH I82
J 0
(-7525 1225);
DISPLAY 0.872340 (-7525 1225);
PAINT AQUA (-7525 1225);
DISPLAY INVISIBLE (-7525 1225);
FORCEADD Q_RES..1
(-4675 2050);
FORCEPROP 1 LAST LOCATION PR190
J 0
(-4700 2100);
DISPLAY 0.489362 (-4700 2100);
PAINT SKYBLUE (-4700 2100);
FORCEPROP 0 LAST $SEC 1
J 0
(-4650 2125);
DISPLAY 0.680851 (-4650 2125);
PAINT MONO (-4650 2125);
DISPLAY INVISIBLE (-4650 2125);
FORCEPROP 0 LAST CDS_SEC 1
J 0
(-4650 2125);
DISPLAY 1.021277 (-4650 2125);
DISPLAY INVISIBLE (-4650 2125);
FORCEPROP 1 LASTPIN (-4775 2050) $PN 1
J 0
(-4763 2062);
DISPLAY 0.489362 (-4763 2062);
PAINT MONO (-4763 2062);
FORCEPROP 1 LASTPIN (-4575 2050) $PN 2
J 0
(-4613 2062);
DISPLAY 0.489362 (-4613 2062);
PAINT MONO (-4613 2062);
FORCEPROP 1 LAST WATTAGE 1/16W
J 0
(-4575 2000);
DISPLAY 0.489362 (-4575 2000);
PAINT SKYBLUE (-4575 2000);
FORCEPROP 1 LAST TOLERANCE 1%
J 0
(-4550 2075);
DISPLAY 0.489362 (-4550 2075);
PAINT SKYBLUE (-4550 2075);
FORCEPROP 1 LAST PACK_TYPE 0402LF
J 0
(-4575 1950);
DISPLAY 0.489362 (-4575 1950);
PAINT SKYBLUE (-4575 1950);
FORCEPROP 1 LAST VALUE 5.6
J 2
(-4800 2075);
DISPLAY 0.489362 (-4800 2075);
PAINT SKYBLUE (-4800 2075);
FORCEPROP 1 LAST MATERIAL CHIP
J 0
(-4925 1950);
DISPLAY 0.489362 (-4925 1950);
PAINT SKYBLUE (-4925 1950);
FORCEPROP 2 LAST CDS_LIB pure_quanta
J 0
(-4675 2050);
DISPLAY INVISIBLE (-4675 2050);
FORCEPROP 1 LAST PATH I83
J 0
(-4725 2200);
DISPLAY 0.978723 (-4725 2200);
PAINT WHITE (-4725 2200);
DISPLAY INVISIBLE (-4725 2200);
FORCEPROP 1 LAST PART_NUMBER CS-5602FB01
J 0
(-4925 2000);
DISPLAY 0.489362 (-4925 2000);
PAINT SKYBLUE (-4925 2000);
DISPLAY INVISIBLE (-4925 2000);
FORCEADD Q_CAPP..1
(-3100 2900);
FORCEPROP 1 LAST LOCATION PC105
J 0
(-3050 3000);
DISPLAY 0.489362 (-3050 3000);
PAINT SKYBLUE (-3050 3000);
FORCEPROP 0 LAST $SEC 1
J 0
(-3050 3050);
DISPLAY 0.680851 (-3050 3050);
PAINT MONO (-3050 3050);
DISPLAY INVISIBLE (-3050 3050);
FORCEPROP 0 LAST CDS_SEC 1
J 0
(-3050 3050);
DISPLAY 1.021277 (-3050 3050);
DISPLAY INVISIBLE (-3050 3050);
FORCEPROP 1 LASTPIN (-3100 3000) $PN 1
J 0
(-3090 2985);
DISPLAY 0.489362 (-3090 2985);
PAINT MONO (-3090 2985);
FORCEPROP 1 LASTPIN (-3100 2800) $PN 2
J 0
(-3090 2785);
DISPLAY 0.489362 (-3090 2785);
PAINT MONO (-3090 2785);
FORCEPROP 1 LAST VOLTAGE 4V
J 0
(-3050 2850);
DISPLAY 0.489362 (-3050 2850);
PAINT SKYBLUE (-3050 2850);
FORCEPROP 1 LAST TOLERANCE 20%
J 0
(-3050 2900);
DISPLAY 0.489362 (-3050 2900);
PAINT SKYBLUE (-3050 2900);
FORCEPROP 1 LAST VALUE 220UF
J 0
(-3050 2950);
DISPLAY 0.489362 (-3050 2950);
PAINT SKYBLUE (-3050 2950);
FORCEPROP 1 LAST MATERIAL SPCAP
J 0
(-3050 2800);
DISPLAY 0.489362 (-3050 2800);
PAINT SKYBLUE (-3050 2800);
FORCEPROP 1 LAST PACK_TYPE SMLF
J 0
(-3050 2750);
DISPLAY 0.489362 (-3050 2750);
PAINT SKYBLUE (-3050 2750);
FORCEPROP 2 LAST CDS_LIB pure_quanta
J 0
(-3100 2900);
DISPLAY INVISIBLE (-3100 2900);
FORCEPROP 1 LAST PATH I84
J 0
(-3050 3050);
DISPLAY 0.978723 (-3050 3050);
DISPLAY INVISIBLE (-3050 3050);
FORCEPROP 1 LAST PART_NUMBER CH122KM8801
J 0
(-3050 2700);
DISPLAY 0.489362 (-3050 2700);
PAINT SKYBLUE (-3050 2700);
DISPLAY INVISIBLE (-3050 2700);
FORCEADD Q_CAP..1
(-2025 4275);
FORCEPROP 1 LAST LOCATION PC278
J 0
(-1975 4375);
DISPLAY 0.489362 (-1975 4375);
PAINT SKYBLUE (-1975 4375);
FORCEPROP 0 LAST $SEC 1
J 0
(-1975 4400);
DISPLAY 0.680851 (-1975 4400);
PAINT MONO (-1975 4400);
DISPLAY INVISIBLE (-1975 4400);
FORCEPROP 0 LAST CDS_SEC 1
J 0
(-1975 4400);
DISPLAY 1.021277 (-1975 4400);
DISPLAY INVISIBLE (-1975 4400);
FORCEPROP 1 LASTPIN (-2025 4375) $PN 1
J 0
(-2015 4355);
DISPLAY 0.489362 (-2015 4355);
PAINT MONO (-2015 4355);
FORCEPROP 1 LASTPIN (-2025 4175) $PN 2
J 0
(-2015 4155);
DISPLAY 0.489362 (-2015 4155);
PAINT MONO (-2015 4155);
FORCEPROP 1 LAST MATERIAL X7R
J 0
(-1975 4175);
DISPLAY 0.489362 (-1975 4175);
PAINT SKYBLUE (-1975 4175);
FORCEPROP 1 LAST TOLERANCE 10%
J 0
(-1975 4225);
DISPLAY 0.489362 (-1975 4225);
PAINT SKYBLUE (-1975 4225);
FORCEPROP 1 LAST VALUE 0.1UF
J 0
(-1975 4325);
DISPLAY 0.489362 (-1975 4325);
PAINT SKYBLUE (-1975 4325);
FORCEPROP 1 LAST VOLTAGE 25V
J 0
(-1975 4275);
DISPLAY 0.489362 (-1975 4275);
PAINT SKYBLUE (-1975 4275);
FORCEPROP 1 LAST PACK_TYPE 0402
J 0
(-1975 4075);
DISPLAY 0.489362 (-1975 4075);
PAINT SKYBLUE (-1975 4075);
FORCEPROP 2 LAST CDS_LIB pure_quanta
J 0
(-2025 4275);
DISPLAY INVISIBLE (-2025 4275);
FORCEPROP 1 LAST PATH I85
J 0
(-1975 4425);
DISPLAY 0.978723 (-1975 4425);
PAINT WHITE (-1975 4425);
DISPLAY INVISIBLE (-1975 4425);
FORCEPROP 1 LAST PART_NUMBER CH4104K1B00
J 0
(-1975 4125);
DISPLAY 0.489362 (-1975 4125);
PAINT SKYBLUE (-1975 4125);
DISPLAY INVISIBLE (-1975 4125);
FORCEADD UNIVERSAL_GND..1
(-2550 5050);
FORCEPROP 3 LASTPIN (-2550 5100) SIG_NAME GND\g
J 0
(-2540 5110);
DISPLAY 0.659574 (-2540 5110);
PAINT MONO (-2540 5110);
DISPLAY INVISIBLE (-2540 5110);
FORCEPROP 2 LAST CDS_LIB pure_quanta_power
J 0
(-2550 5050);
DISPLAY INVISIBLE (-2550 5050);
FORCEPROP 1 LAST HDL_POWER GND
J 1
(-2525 4975);
DISPLAY 0.872340 (-2525 4975);
PAINT GREEN (-2525 4975);
DISPLAY INVISIBLE (-2525 4975);
FORCEPROP 1 LAST PATH I86
J 0
(-2475 5050);
DISPLAY 0.872340 (-2475 5050);
PAINT AQUA (-2475 5050);
DISPLAY INVISIBLE (-2475 5050);
FORCEADD VCC_CORE..1
(-4025 5650);
FORCEPROP 3 LASTPIN (-4025 5600) SIG_NAME SW_P12V_AUX_PVDDCR_CPU0_P1_FLT\g
J 0
(-4015 5610);
DISPLAY 0.659574 (-4015 5610);
PAINT MONO (-4015 5610);
DISPLAY INVISIBLE (-4015 5610);
FORCEPROP 1 LAST HDL_POWER SW_P12V_AUX_PVDDCR_CPU0_P1_FLT
J 1
(-4025 5700);
DISPLAY 0.489362 (-4025 5700);
PAINT GREEN (-4025 5700);
FORCEPROP 2 LAST CDS_LIB pure_quanta_power
J 0
(-4025 5650);
DISPLAY INVISIBLE (-4025 5650);
FORCEPROP 1 LAST PATH I87
J 0
(-3975 5675);
DISPLAY 0.872340 (-3975 5675);
PAINT AQUA (-3975 5675);
DISPLAY INVISIBLE (-3975 5675);
FORCEADD ISL99390FRZTR5935..1
(-6125 4450);
FORCEPROP 1 LAST LOCATION PU4
J 0
(-6425 5325);
DISPLAY 0.489362 (-6425 5325);
PAINT SKYBLUE (-6425 5325);
FORCEPROP 0 LAST $SEC 1
J 0
(-6425 5475);
DISPLAY 0.680851 (-6425 5475);
PAINT MONO (-6425 5475);
DISPLAY INVISIBLE (-6425 5475);
FORCEPROP 0 LAST CDS_SEC 1
J 0
(-6425 5475);
DISPLAY 1.021277 (-6425 5475);
DISPLAY INVISIBLE (-6425 5475);
FORCEPROP 0 LASTPIN (-5725 4000) $PN 2
J 0
(-5715 4010);
DISPLAY 0.489362 (-5715 4010);
PAINT MONO (-5715 4010);
FORCEPROP 0 LASTPIN (-5725 4800) $PN 33
J 0
(-5715 4810);
DISPLAY 0.489362 (-5715 4810);
PAINT MONO (-5715 4810);
FORCEPROP 0 LASTPIN (-6575 4200) $PN 31
J 2
(-6585 4210);
DISPLAY 0.489362 (-6585 4210);
PAINT MONO (-6585 4210);
FORCEPROP 0 LASTPIN (-6575 4600) $PN 35
J 2
(-6585 4610);
DISPLAY 0.489362 (-6585 4610);
PAINT MONO (-6585 4610);
FORCEPROP 0 LASTPIN (-5725 4150) $PN 6
J 0
(-5715 4160);
DISPLAY 0.489362 (-5715 4160);
PAINT MONO (-5715 4160);
FORCEPROP 0 LASTPIN (-5725 4100) $PN 41
J 0
(-5715 4110);
DISPLAY 0.489362 (-5715 4110);
PAINT MONO (-5715 4110);
FORCEPROP 0 LASTPIN (-6575 4450) $PN 38
J 2
(-6585 4460);
DISPLAY 0.489362 (-6585 4460);
PAINT MONO (-6585 4460);
FORCEPROP 0 LASTPIN (-6575 4150) $PN 37
J 2
(-6585 4160);
DISPLAY 0.489362 (-6585 4160);
PAINT MONO (-6585 4160);
FORCEPROP 0 LASTPIN (-5725 3950) $PN 5
J 0
(-5715 3960);
DISPLAY 0.489362 (-5715 3960);
PAINT MONO (-5715 3960);
FORCEPROP 0 LASTPIN (-5725 3900) $PN 7_9-20_24
J 0
(-5715 3910);
DISPLAY 0.489362 (-5715 3910);
PAINT MONO (-5715 3910);
FORCEPROP 0 LASTPIN (-5725 3850) $PN 40
J 0
(-5715 3860);
DISPLAY 0.489362 (-5715 3860);
PAINT MONO (-5715 3860);
FORCEPROP 0 LASTPIN (-5725 4550) $PN 32
J 0
(-5715 4560);
DISPLAY 0.489362 (-5715 4560);
PAINT MONO (-5715 4560);
FORCEPROP 0 LASTPIN (-6575 5100) $PN 4
J 2
(-6585 5110);
DISPLAY 0.489362 (-6585 5110);
PAINT MONO (-6585 5110);
FORCEPROP 0 LASTPIN (-6575 3850) $PN 34
J 2
(-6585 3860);
DISPLAY 0.489362 (-6585 3860);
PAINT MONO (-6585 3860);
FORCEPROP 0 LASTPIN (-6575 4350) $PN 39
J 2
(-6585 4360);
DISPLAY 0.489362 (-6585 4360);
PAINT MONO (-6585 4360);
FORCEPROP 0 LASTPIN (-5725 4450) $PN 10_19
J 0
(-5715 4460);
DISPLAY 0.489362 (-5715 4460);
PAINT MONO (-5715 4460);
FORCEPROP 0 LASTPIN (-6575 3950) $PN 36
J 2
(-6585 3960);
DISPLAY 0.489362 (-6585 3960);
PAINT MONO (-6585 3960);
FORCEPROP 0 LASTPIN (-6575 4800) $PN 3
J 2
(-6585 4810);
DISPLAY 0.489362 (-6585 4810);
PAINT MONO (-6585 4810);
FORCEPROP 0 LASTPIN (-5725 5100) $PN 25_29
J 0
(-5715 5110);
DISPLAY 0.489362 (-5715 5110);
PAINT MONO (-5715 5110);
FORCEPROP 0 LASTPIN (-5725 5050) $PN 30
J 0
(-5715 5060);
DISPLAY 0.489362 (-5715 5060);
PAINT MONO (-5715 5060);
FORCEPROP 0 LASTPIN (-5725 4200) $PN 1
J 0
(-5715 4210);
DISPLAY 0.489362 (-5715 4210);
PAINT MONO (-5715 4210);
FORCEPROP 1 LAST MATERIAL IC
J 0
(-6425 5175);
DISPLAY 0.489362 (-6425 5175);
PAINT SKYBLUE (-6425 5175);
FORCEPROP 2 LAST VALUE ISL99390FRZ-TR5935
J 0
(-6425 5375);
DISPLAY 0.489362 (-6425 5375);
PAINT SKYBLUE (-6425 5375);
FORCEPROP 2 LAST PART_TYPE SMLF
J 0
(-6425 5425);
DISPLAY 1.021277 (-6425 5425);
FORCEPROP 1 LAST NEEDS_NO_SIZE TRUE
J 0
(-6125 4450);
DISPLAY 0.723404 (-6125 4450);
PAINT GREEN (-6125 4450);
DISPLAY INVISIBLE (-6125 4450);
FORCEPROP 1 LAST CDS_LMAN_SYM_OUTLINE -300,700,250,-650
J 0
(-6125 4450);
DISPLAY 0.468085 (-6125 4450);
PAINT GREEN (-6125 4450);
DISPLAY INVISIBLE (-6125 4450);
FORCEPROP 2 LAST CDS_LIB pure_quanta
J 0
(-6125 4450);
DISPLAY INVISIBLE (-6125 4450);
FORCEPROP 1 LAST PATH I88
J 0
(-6125 4450);
DISPLAY 0.723404 (-6125 4450);
PAINT GREEN (-6125 4450);
DISPLAY INVISIBLE (-6125 4450);
FORCEPROP 1 LAST PART_NUMBER AL099390004
J 0
(-6425 5250);
DISPLAY 0.489362 (-6425 5250);
PAINT SKYBLUE (-6425 5250);
DISPLAY INVISIBLE (-6425 5250);
FORCEADD Q_CAP..1
(-4050 4675);
FORCEPROP 1 LAST LOCATION PC270
J 0
(-4000 4800);
DISPLAY 0.489362 (-4000 4800);
PAINT SKYBLUE (-4000 4800);
FORCEPROP 0 LAST $SEC 1
J 0
(-4000 4825);
DISPLAY 0.680851 (-4000 4825);
PAINT MONO (-4000 4825);
DISPLAY INVISIBLE (-4000 4825);
FORCEPROP 0 LAST CDS_SEC 1
J 0
(-4000 4825);
DISPLAY 1.021277 (-4000 4825);
DISPLAY INVISIBLE (-4000 4825);
FORCEPROP 1 LASTPIN (-4050 4775) $PN 1
J 0
(-4040 4755);
DISPLAY 0.489362 (-4040 4755);
PAINT MONO (-4040 4755);
FORCEPROP 1 LASTPIN (-4050 4575) $PN 2
J 0
(-4040 4555);
DISPLAY 0.489362 (-4040 4555);
PAINT MONO (-4040 4555);
FORCEPROP 1 LAST VALUE 0.22UF
J 0
(-4000 4750);
DISPLAY 0.489362 (-4000 4750);
PAINT SKYBLUE (-4000 4750);
FORCEPROP 1 LAST VOLTAGE 16V
J 0
(-4000 4700);
DISPLAY 0.489362 (-4000 4700);
PAINT SKYBLUE (-4000 4700);
FORCEPROP 1 LAST TOLERANCE 10%
J 0
(-4000 4650);
DISPLAY 0.489362 (-4000 4650);
PAINT SKYBLUE (-4000 4650);
FORCEPROP 1 LAST MATERIAL X7R
J 0
(-4000 4600);
DISPLAY 0.489362 (-4000 4600);
PAINT SKYBLUE (-4000 4600);
FORCEPROP 1 LAST PACK_TYPE 0402
J 0
(-4000 4500);
DISPLAY 0.489362 (-4000 4500);
PAINT SKYBLUE (-4000 4500);
FORCEPROP 2 LAST CDS_LIB pure_quanta
J 0
(-4050 4675);
DISPLAY INVISIBLE (-4050 4675);
FORCEPROP 1 LAST PATH I89
J 0
(-4000 4825);
DISPLAY 0.978723 (-4000 4825);
PAINT WHITE (-4000 4825);
DISPLAY INVISIBLE (-4000 4825);
FORCEPROP 1 LAST PART_NUMBER CH4223K1B00
J 0
(-4000 4550);
DISPLAY 0.489362 (-4000 4550);
PAINT SKYBLUE (-4000 4550);
DISPLAY INVISIBLE (-4000 4550);
FORCEADD Q_CAP..1
(-7575 2050);
FORCEPROP 1 LAST LOCATION PC257
J 0
(-7525 2150);
DISPLAY 0.489362 (-7525 2150);
PAINT SKYBLUE (-7525 2150);
FORCEPROP 0 LAST $SEC 1
J 0
(-7525 2200);
DISPLAY 0.680851 (-7525 2200);
PAINT MONO (-7525 2200);
DISPLAY INVISIBLE (-7525 2200);
FORCEPROP 0 LAST CDS_SEC 1
J 0
(-7525 2200);
DISPLAY 1.021277 (-7525 2200);
DISPLAY INVISIBLE (-7525 2200);
FORCEPROP 1 LASTPIN (-7575 2150) $PN 1
J 0
(-7565 2130);
DISPLAY 0.489362 (-7565 2130);
PAINT MONO (-7565 2130);
FORCEPROP 1 LASTPIN (-7575 1950) $PN 2
J 0
(-7565 1930);
DISPLAY 0.489362 (-7565 1930);
PAINT MONO (-7565 1930);
FORCEPROP 1 LAST MATERIAL X6S
J 0
(-7525 1950);
DISPLAY 0.489362 (-7525 1950);
PAINT SKYBLUE (-7525 1950);
FORCEPROP 1 LAST TOLERANCE 10%
J 0
(-7525 2000);
DISPLAY 0.489362 (-7525 2000);
PAINT SKYBLUE (-7525 2000);
FORCEPROP 1 LAST VALUE 2.2UF
J 0
(-7525 2100);
DISPLAY 0.489362 (-7525 2100);
PAINT SKYBLUE (-7525 2100);
FORCEPROP 1 LAST VOLTAGE 10V
J 0
(-7525 2050);
DISPLAY 0.489362 (-7525 2050);
PAINT SKYBLUE (-7525 2050);
FORCEPROP 1 LAST PACK_TYPE C0402
J 0
(-7525 1850);
DISPLAY 0.489362 (-7525 1850);
PAINT SKYBLUE (-7525 1850);
FORCEPROP 2 LAST CDS_LIB pure_quanta
J 0
(-7575 2050);
DISPLAY INVISIBLE (-7575 2050);
FORCEPROP 1 LAST PATH I9
J 0
(-7525 2200);
DISPLAY 0.978723 (-7525 2200);
PAINT WHITE (-7525 2200);
DISPLAY INVISIBLE (-7525 2200);
FORCEPROP 1 LAST PART_NUMBER CH5222KEB01
J 0
(-7525 1900);
DISPLAY 0.489362 (-7525 1900);
PAINT SKYBLUE (-7525 1900);
DISPLAY INVISIBLE (-7525 1900);
FORCEADD Q_INDUCTOR4P_14..1
(-3325 4325);
FORCEPROP 1 LAST LOCATION PL28
J 0
(-3550 4580);
DISPLAY 0.489362 (-3550 4580);
PAINT SKYBLUE (-3550 4580);
FORCEPROP 0 LAST $SEC 1
J 0
(-3550 4725);
DISPLAY 0.680851 (-3550 4725);
PAINT MONO (-3550 4725);
DISPLAY INVISIBLE (-3550 4725);
FORCEPROP 0 LAST CDS_SEC 1
J 0
(-3550 4725);
DISPLAY 1.021277 (-3550 4725);
DISPLAY INVISIBLE (-3550 4725);
FORCEPROP 0 LASTPIN (-3725 4450) $PN 1
J 2
(-3735 4460);
DISPLAY 0.489362 (-3735 4460);
PAINT MONO (-3735 4460);
FORCEPROP 0 LASTPIN (-3725 4200) $PN 2
J 2
(-3735 4210);
DISPLAY 0.489362 (-3735 4210);
PAINT MONO (-3735 4210);
FORCEPROP 0 LASTPIN (-2925 4200) $PN 3
J 0
(-2915 4210);
DISPLAY 0.489362 (-2915 4210);
PAINT MONO (-2915 4210);
FORCEPROP 0 LASTPIN (-2925 4450) $PN 4
J 0
(-2915 4460);
DISPLAY 0.489362 (-2915 4460);
PAINT MONO (-2915 4460);
FORCEPROP 2 LAST PART_TYPE SMLF
J 0
(-3550 4675);
DISPLAY 1.021277 (-3550 4675);
FORCEPROP 2 LAST VALUE 150NH
J 0
(-3550 4625);
DISPLAY 0.489362 (-3550 4625);
PAINT SKYBLUE (-3550 4625);
FORCEPROP 1 LAST MATERIAL IND
J 0
(-3550 4535);
DISPLAY 0.489362 (-3550 4535);
PAINT SKYBLUE (-3550 4535);
FORCEPROP 2 LAST CDS_LIB pure_quanta
J 0
(-3325 4325);
DISPLAY INVISIBLE (-3325 4325);
FORCEPROP 1 LAST NEEDS_NO_SIZE TRUE
J 0
(-3325 4325);
DISPLAY 0.468085 (-3325 4325);
PAINT GREEN (-3325 4325);
DISPLAY INVISIBLE (-3325 4325);
FORCEPROP 1 LAST PATH I90
J 0
(-3125 4480);
DISPLAY 0.723404 (-3125 4480);
PAINT GREEN (-3125 4480);
DISPLAY INVISIBLE (-3125 4480);
FORCEPROP 1 LAST PART_NUMBER CV+15^0TZ04
J 0
(-3550 4485);
DISPLAY 0.489362 (-3550 4485);
PAINT SKYBLUE (-3550 4485);
DISPLAY INVISIBLE (-3550 4485);
FORCEADD ISL99390FRZTR5935..1
(-6100 1700);
FORCEPROP 1 LAST LOCATION PU26
J 0
(-6400 2575);
DISPLAY 0.489362 (-6400 2575);
PAINT SKYBLUE (-6400 2575);
FORCEPROP 0 LAST $SEC 1
J 0
(-6400 2725);
DISPLAY 0.680851 (-6400 2725);
PAINT MONO (-6400 2725);
DISPLAY INVISIBLE (-6400 2725);
FORCEPROP 2 LAST CDS_SEC 1
J 0
(-6400 2725);
DISPLAY 1.021277 (-6400 2725);
DISPLAY INVISIBLE (-6400 2725);
FORCEPROP 0 LASTPIN (-5700 1250) $PN 2
J 0
(-5690 1260);
DISPLAY 0.489362 (-5690 1260);
PAINT MONO (-5690 1260);
FORCEPROP 0 LASTPIN (-5700 2050) $PN 33
J 0
(-5690 2060);
DISPLAY 0.489362 (-5690 2060);
PAINT MONO (-5690 2060);
FORCEPROP 0 LASTPIN (-6550 1450) $PN 31
J 2
(-6560 1460);
DISPLAY 0.489362 (-6560 1460);
PAINT MONO (-6560 1460);
FORCEPROP 0 LASTPIN (-6550 1850) $PN 35
J 2
(-6560 1860);
DISPLAY 0.489362 (-6560 1860);
PAINT MONO (-6560 1860);
FORCEPROP 0 LASTPIN (-5700 1400) $PN 6
J 0
(-5690 1410);
DISPLAY 0.489362 (-5690 1410);
PAINT MONO (-5690 1410);
FORCEPROP 0 LASTPIN (-5700 1350) $PN 41
J 0
(-5690 1360);
DISPLAY 0.489362 (-5690 1360);
PAINT MONO (-5690 1360);
FORCEPROP 0 LASTPIN (-6550 1700) $PN 38
J 2
(-6560 1710);
DISPLAY 0.489362 (-6560 1710);
PAINT MONO (-6560 1710);
FORCEPROP 0 LASTPIN (-6550 1400) $PN 37
J 2
(-6560 1410);
DISPLAY 0.489362 (-6560 1410);
PAINT MONO (-6560 1410);
FORCEPROP 0 LASTPIN (-5700 1200) $PN 5
J 0
(-5690 1210);
DISPLAY 0.489362 (-5690 1210);
PAINT MONO (-5690 1210);
FORCEPROP 0 LASTPIN (-5700 1150) $PN 7_9-20_24
J 0
(-5690 1160);
DISPLAY 0.489362 (-5690 1160);
PAINT MONO (-5690 1160);
FORCEPROP 0 LASTPIN (-5700 1100) $PN 40
J 0
(-5690 1110);
DISPLAY 0.489362 (-5690 1110);
PAINT MONO (-5690 1110);
FORCEPROP 0 LASTPIN (-5700 1800) $PN 32
J 0
(-5690 1810);
DISPLAY 0.489362 (-5690 1810);
PAINT MONO (-5690 1810);
FORCEPROP 0 LASTPIN (-6550 2350) $PN 4
J 2
(-6560 2360);
DISPLAY 0.489362 (-6560 2360);
PAINT MONO (-6560 2360);
FORCEPROP 0 LASTPIN (-6550 1100) $PN 34
J 2
(-6560 1110);
DISPLAY 0.489362 (-6560 1110);
PAINT MONO (-6560 1110);
FORCEPROP 0 LASTPIN (-6550 1600) $PN 39
J 2
(-6560 1610);
DISPLAY 0.489362 (-6560 1610);
PAINT MONO (-6560 1610);
FORCEPROP 0 LASTPIN (-5700 1700) $PN 10_19
J 0
(-5690 1710);
DISPLAY 0.489362 (-5690 1710);
PAINT MONO (-5690 1710);
FORCEPROP 0 LASTPIN (-6550 1200) $PN 36
J 2
(-6560 1210);
DISPLAY 0.489362 (-6560 1210);
PAINT MONO (-6560 1210);
FORCEPROP 0 LASTPIN (-6550 2050) $PN 3
J 2
(-6560 2060);
DISPLAY 0.489362 (-6560 2060);
PAINT MONO (-6560 2060);
FORCEPROP 0 LASTPIN (-5700 2350) $PN 25_29
J 0
(-5690 2360);
DISPLAY 0.489362 (-5690 2360);
PAINT MONO (-5690 2360);
FORCEPROP 0 LASTPIN (-5700 2300) $PN 30
J 0
(-5690 2310);
DISPLAY 0.489362 (-5690 2310);
PAINT MONO (-5690 2310);
FORCEPROP 0 LASTPIN (-5700 1450) $PN 1
J 0
(-5690 1460);
DISPLAY 0.489362 (-5690 1460);
PAINT MONO (-5690 1460);
FORCEPROP 2 LAST PART_TYPE SMLF
J 0
(-6400 2675);
DISPLAY 1.021277 (-6400 2675);
FORCEPROP 1 LAST MATERIAL IC
J 0
(-6400 2425);
DISPLAY 0.489362 (-6400 2425);
PAINT SKYBLUE (-6400 2425);
FORCEPROP 2 LAST VALUE ISL99390FRZ-TR5935
J 0
(-6400 2625);
DISPLAY 0.489362 (-6400 2625);
PAINT SKYBLUE (-6400 2625);
FORCEPROP 2 LAST CDS_LIB pure_quanta
J 0
(-6100 1700);
DISPLAY INVISIBLE (-6100 1700);
FORCEPROP 1 LAST CDS_LMAN_SYM_OUTLINE -300,700,250,-650
J 0
(-6100 1700);
DISPLAY 0.468085 (-6100 1700);
PAINT GREEN (-6100 1700);
DISPLAY INVISIBLE (-6100 1700);
FORCEPROP 1 LAST NEEDS_NO_SIZE TRUE
J 0
(-6100 1700);
DISPLAY 0.723404 (-6100 1700);
PAINT GREEN (-6100 1700);
DISPLAY INVISIBLE (-6100 1700);
FORCEPROP 1 LAST PATH I91
J 0
(-6100 1700);
DISPLAY 0.723404 (-6100 1700);
PAINT GREEN (-6100 1700);
DISPLAY INVISIBLE (-6100 1700);
FORCEPROP 1 LAST PART_NUMBER AL099390004
J 0
(-6400 2500);
DISPLAY 0.489362 (-6400 2500);
PAINT SKYBLUE (-6400 2500);
DISPLAY INVISIBLE (-6400 2500);
FORCEADD DNS..1
(-7300 4125);
PAINT RED (-7300 4125);
FORCEPROP 2 LAST CDS_LIB mstr_misc
J 0
(-7300 4125);
DISPLAY INVISIBLE (-7300 4125);
FORCEPROP 1 LAST COMMENT_BODY TRUE
R 1
J 0
(-7225 3900);
DISPLAY 0.872340 (-7225 3900);
PAINT GREEN (-7225 3900);
DISPLAY INVISIBLE (-7225 3900);
FORCEADD DNS..1
(-4675 1000);
PAINT RED (-4675 1000);
FORCEPROP 2 LAST CDS_LIB mstr_misc
J 0
(-4675 1000);
DISPLAY INVISIBLE (-4675 1000);
FORCEPROP 1 LAST COMMENT_BODY TRUE
R 1
J 0
(-4600 775);
DISPLAY 0.872340 (-4600 775);
PAINT GREEN (-4600 775);
DISPLAY INVISIBLE (-4600 775);
FORCEADD DNS..1
(-4825 3775);
PAINT RED (-4825 3775);
FORCEPROP 2 LAST CDS_LIB mstr_misc
J 0
(-4825 3775);
DISPLAY INVISIBLE (-4825 3775);
FORCEPROP 1 LAST COMMENT_BODY TRUE
R 1
J 0
(-4750 3550);
DISPLAY 0.872340 (-4750 3550);
PAINT GREEN (-4750 3550);
DISPLAY INVISIBLE (-4750 3550);
FORCEADD DNS..1
(-7900 5775);
PAINT RED (-7900 5775);
FORCEPROP 2 LAST CDS_LIB mstr_misc
J 0
(-7900 5775);
DISPLAY INVISIBLE (-7900 5775);
FORCEPROP 1 LAST COMMENT_BODY TRUE
R 1
J 0
(-7825 5550);
DISPLAY 0.872340 (-7825 5550);
PAINT GREEN (-7825 5550);
DISPLAY INVISIBLE (-7825 5550);
FORCEADD DNS..1
(-4825 4250);
PAINT RED (-4825 4250);
FORCEPROP 2 LAST CDS_LIB mstr_misc
J 0
(-4825 4250);
DISPLAY INVISIBLE (-4825 4250);
FORCEPROP 1 LAST COMMENT_BODY TRUE
R 1
J 0
(-4750 4025);
DISPLAY 0.872340 (-4750 4025);
PAINT GREEN (-4750 4025);
DISPLAY INVISIBLE (-4750 4025);
FORCEADD DNS..1
(-7275 1375);
PAINT RED (-7275 1375);
FORCEPROP 2 LAST CDS_LIB mstr_misc
J 0
(-7275 1375);
DISPLAY INVISIBLE (-7275 1375);
FORCEPROP 1 LAST COMMENT_BODY TRUE
R 1
J 0
(-7200 1150);
DISPLAY 0.872340 (-7200 1150);
PAINT GREEN (-7200 1150);
DISPLAY INVISIBLE (-7200 1150);
FORCEADD DNS..1
(-4675 1500);
PAINT RED (-4675 1500);
FORCEPROP 2 LAST CDS_LIB mstr_misc
J 0
(-4675 1500);
DISPLAY INVISIBLE (-4675 1500);
FORCEPROP 1 LAST COMMENT_BODY TRUE
R 1
J 0
(-4600 1275);
DISPLAY 0.872340 (-4600 1275);
PAINT GREEN (-4600 1275);
DISPLAY INVISIBLE (-4600 1275);
FORCEADD QUANTA_TITLE_BLOCK_C..1
(-475 -450);
FORCEPROP 0 LAST CDS_CON_LAST_MODIFIED Thu Sep 14 16:12:20 2023
J 0
(-2360 -435);
DISPLAY INVISIBLE (-2360 -435);
FORCEPROP 1 LAST CUSTOM_TXT_CDS <CON_LAST_MODIFIED>
J 0
(-2360 -435);
DISPLAY 0.978723 (-2360 -435);
FORCEPROP 2 LAST CUSTOM_TXT_CDS <XR_PAGE_TITLE>
J 0
(-8365 4800);
DISPLAY 0.638298 (-8365 4800);
PAINT PINK (-8365 4800);
DISPLAY INVISIBLE (-8365 4800);
FORCEPROP 1 LAST CUSTOM_TXT_CDS <NAME_2>
J 0
(-3650 -400);
FORCEPROP 1 LAST CUSTOM_TXT_CDS <NAME_1>
J 0
(-3650 -275);
FORCEPROP 1 LAST CUSTOM_TXT_CDS <Q_NUMBER>
J 0
(-1878 -347);
DISPLAY 1.212766 (-1878 -347);
FORCEPROP 1 LAST CUSTOM_TXT_CDS <Q_PROJ>
J 0
(-2857 -348);
DISPLAY 1.212766 (-2857 -348);
FORCEPROP 1 LAST CUSTOM_TXT_CDS <Q_REV>
J 0
(-659 -347);
DISPLAY 1.212766 (-659 -347);
FORCEPROP 1 LAST CUSTOM_TXT_CDS <CON_PAGE_NUM> OF <CON_TOTAL_PAGES>
J 0
(-921 -432);
DISPLAY 0.978723 (-921 -432);
FORCEPROP 1 LAST Q_TITLE PVDDCR_CPU0_P1 VR PHASE 1&2
J 0
(-9800 -400);
DISPLAY 2.446809 (-9800 -400);
PAINT GREEN (-9800 -400);
FORCEPROP 1 LAST CDS_LMAN_SYM_OUTLINE -9475,6775,100,-125
J 0
(-475 -450);
DISPLAY 0.468085 (-475 -450);
PAINT GREEN (-475 -450);
DISPLAY INVISIBLE (-475 -450);
FORCEPROP 2 LAST CDS_LIB pure_quanta
J 0
(-475 -450);
DISPLAY INVISIBLE (-475 -450);
FORCEPROP 2 LAST PAGE_BORDER TRUE
J 0
(-8365 4800);
DISPLAY 0.638298 (-8365 4800);
PAINT PINK (-8365 4800);
DISPLAY INVISIBLE (-8365 4800);
FORCEPROP 2 LAST CDS_XR_PAGE_TITLE CR-211 : @T6G_MB_LIB.T6G(SCH_1):PAGE211
J 0
(-8365 4800);
DISPLAY 0.638298 (-8365 4800);
PAINT PINK (-8365 4800);
DISPLAY INVISIBLE (-8365 4800);
FORCEPROP 1 LAST Q_DEPT BU9
J 1
(-4238 -401);
DISPLAY 1.957447 (-4238 -401);
PAINT GREEN (-4238 -401);
DISPLAY INVISIBLE (-4238 -401);
FORCEPROP 1 LAST COMMENT_BODY TRUE
J 0
(-463 -463);
DISPLAY 0.978723 (-463 -463);
PAINT GREEN (-463 -463);
DISPLAY INVISIBLE (-463 -463);
WIRE 16 -1 (-7575 1950)(-7575 1900);
WIRE 16 -1 (-7225 2525)(-7225 2400);
WIRE 16 -1 (-7950 4075)(-7950 3950);
WIRE 16 -1 (-7400 4150)(-7625 4150);
WIRE 16 -1 (-7625 4150)(-7625 4025);
WIRE 16 -1 (-4650 900)(-4650 825);
WIRE 16 -1 (-4800 3675)(-4800 3600);
WIRE 16 -1 (-7600 4700)(-7600 4650);
WIRE 16 -1 (-8250 5900)(-8250 5850);
WIRE 16 -1 (-7250 5275)(-7250 5150);
WIRE 16 -1 (-7900 5900)(-7900 5850);
WIRE 16 -1 (-7925 1325)(-7925 1200);
WIRE 16 -1 (-7375 1400)(-7600 1400);
WIRE 16 -1 (-7600 1400)(-7600 1275);
WIRE 16 -1 (-2550 5250)(-2550 5100);
WIRE 16 -1 (-7925 1525)(-7925 1600);
WIRE 16 -1 (-6550 1600)(-7925 1600);
FORCEPROP 2 LAST SIG_NAME PVDDCR_CPU0_P1_VCCS
J 2
(-6610 1610);
DISPLAY 0.489362 (-6610 1610);
WIRE 16 -1 (-8100 1600)(-7925 1600);
WIRE 16 -1 (-7575 2225)(-7100 2225);
WIRE 16 -1 (-7575 2500)(-7575 2225);
WIRE 16 -1 (-7575 2225)(-7575 2150);
WIRE 16 -1 (-7100 2225)(-7100 2050);
FORCEPROP 2 LAST SIG_NAME PVDDCR_CPU0_P1_VCC2
J 2
(-6635 2060);
DISPLAY 0.489362 (-6635 2060);
FORCEPROP 2 LASTPROP $XRERR UNIQUE?
J 0
(-6875 2060);
DISPLAY 0.638298 (-6875 2060);
PAINT MONO (-6875 2060);
DISPLAY INVISIBLE (-6875 2060);
WIRE 16 -1 (-7100 2050)(-6550 2050);
WIRE 16 -1 (-7100 2050)(-7100 1850);
WIRE 16 -1 (-7100 1850)(-6550 1850);
WIRE 16 -1 (-4200 2825)(-4200 2750);
WIRE 16 -1 (-4200 2750)(-4200 2675);
WIRE 16 -1 (-4500 2750)(-4200 2750);
WIRE 16 -1 (-4500 2750)(-4500 2675);
WIRE 16 -1 (-4825 2750)(-4500 2750);
WIRE 16 -1 (-4825 2675)(-4825 2750);
WIRE 16 -1 (-5150 2750)(-4825 2750);
WIRE 16 -1 (-5150 2675)(-5150 2750);
WIRE 16 -1 (-5475 2750)(-5150 2750);
WIRE 16 -1 (-5475 2675)(-5475 2750);
WIRE 16 -1 (-5600 2750)(-5475 2750);
WIRE 16 -1 (-5600 2750)(-5600 2350);
WIRE 16 -1 (-5600 2350)(-5600 2300);
WIRE 16 -1 (-5700 2350)(-5600 2350);
WIRE 16 -1 (-5600 2300)(-5700 2300);
WIRE 16 -1 (-4500 2475)(-4500 2350);
WIRE 16 -1 (-4200 2350)(-4500 2350);
WIRE 16 -1 (-4825 2350)(-4500 2350);
WIRE 16 -1 (-4825 2475)(-4825 2350);
WIRE 16 -1 (-5150 2350)(-4825 2350);
WIRE 16 -1 (-4200 2475)(-4200 2350);
WIRE 16 -1 (-4200 2350)(-4200 2275);
WIRE 16 -1 (-5150 2475)(-5150 2350);
WIRE 16 -1 (-5475 2350)(-5150 2350);
WIRE 16 -1 (-5475 2475)(-5475 2350);
WIRE 16 -1 (-5700 2050)(-4775 2050);
FORCEPROP 2 LAST SIG_NAME SW_PVDDCR_CPU0_P1_BOOT2
J 0
(-5585 2060);
DISPLAY 0.489362 (-5585 2060);
FORCEPROP 2 LASTPROP $XRERR UNIQUE?
J 0
(-5825 2060);
DISPLAY 0.638298 (-5825 2060);
PAINT MONO (-5825 2060);
DISPLAY INVISIBLE (-5825 2060);
WIRE 16 -1 (-3675 1825)(-3675 1800);
WIRE 16 -1 (-3675 1800)(-5700 1800);
FORCEPROP 2 LAST SIG_NAME SW_PVDDCR_CPU0_P1_PH2
J 0
(-5585 1810);
DISPLAY 0.489362 (-5585 1810);
FORCEPROP 2 LASTPROP $XRERR UNIQUE?
J 0
(-5825 1810);
DISPLAY 0.638298 (-5825 1810);
PAINT MONO (-5825 1810);
DISPLAY INVISIBLE (-5825 1810);
WIRE 16 -1 (-5725 4200)(-5025 4200);
WIRE 16 -1 (-5025 3475)(-5025 4200);
WIRE 16 -1 (-4425 3475)(-5025 3475);
FORCEPROP 2 LAST SIG_NAME PVDDCR_CPU0_P1_VOS1
J 0
(-5610 4225);
DISPLAY 0.489362 (-5610 4225);
FORCEPROP 2 LASTPROP $XRERR UNIQUE?
J 0
(-5850 4225);
DISPLAY 0.638298 (-5850 4225);
PAINT MONO (-5850 4225);
DISPLAY INVISIBLE (-5850 4225);
WIRE 16 -1 (-4800 4350)(-4800 4450);
WIRE 16 -1 (-4800 4450)(-3725 4450);
WIRE 16 -1 (-5725 4450)(-4800 4450);
FORCEPROP 2 LAST SIG_NAME SW_PVDDCR_CPU0_P1_SW1
J 0
(-5610 4460);
DISPLAY 0.489362 (-5610 4460);
FORCEPROP 2 LASTPROP $XRERR UNIQUE?
J 0
(-5850 4460);
DISPLAY 0.638298 (-5850 4460);
PAINT MONO (-5850 4460);
DISPLAY INVISIBLE (-5850 4460);
WIRE 16 -1 (-4050 4575)(-4050 4550);
WIRE 16 -1 (-4050 4550)(-5725 4550);
FORCEPROP 2 LAST SIG_NAME SW_PVDDCR_CPU0_P1_PH1
J 0
(-5610 4560);
DISPLAY 0.489362 (-5610 4560);
FORCEPROP 2 LASTPROP $XRERR UNIQUE?
J 0
(-5850 4560);
DISPLAY 0.638298 (-5850 4560);
PAINT MONO (-5850 4560);
DISPLAY INVISIBLE (-5850 4560);
WIRE 16 -1 (-3000 5500)(-3475 5500);
WIRE 16 -1 (-3475 5500)(-3475 5425);
WIRE 16 -1 (-3850 5500)(-3475 5500);
WIRE 16 -1 (-3850 5500)(-3850 5425);
WIRE 16 -1 (-3850 5500)(-4025 5500);
WIRE 16 -1 (-4025 5600)(-4025 5500);
WIRE 16 -1 (-4025 5500)(-4200 5500);
WIRE 16 -1 (-4200 5500)(-4200 5425);
WIRE 16 -1 (-4500 5500)(-4200 5500);
WIRE 16 -1 (-4500 5500)(-4500 5425);
WIRE 16 -1 (-4825 5500)(-4500 5500);
WIRE 16 -1 (-4825 5425)(-4825 5500);
WIRE 16 -1 (-5150 5500)(-4825 5500);
WIRE 16 -1 (-5150 5425)(-5150 5500);
WIRE 16 -1 (-5475 5500)(-5150 5500);
WIRE 16 -1 (-5475 5425)(-5475 5500);
WIRE 16 -1 (-5625 5500)(-5475 5500);
WIRE 16 -1 (-5625 5500)(-5625 5100);
WIRE 16 -1 (-5625 5100)(-5625 5050);
WIRE 16 -1 (-5725 5100)(-5625 5100);
WIRE 16 -1 (-5625 5050)(-5725 5050);
WIRE 16 -1 (-5725 4800)(-4975 4800);
FORCEPROP 2 LAST SIG_NAME SW_PVDDCR_CPU0_P1_BOOT1
J 0
(-5610 4810);
DISPLAY 0.489362 (-5610 4810);
FORCEPROP 2 LASTPROP $XRERR UNIQUE?
J 0
(-5850 4810);
DISPLAY 0.638298 (-5850 4810);
PAINT MONO (-5850 4810);
DISPLAY INVISIBLE (-5850 4810);
WIRE 16 -1 (-7600 4975)(-7125 4975);
WIRE 16 -1 (-7600 5250)(-7600 4975);
WIRE 16 -1 (-7600 4975)(-7600 4900);
WIRE 16 -1 (-7125 4975)(-7125 4800);
FORCEPROP 2 LAST SIG_NAME PVDDCR_CPU0_P1_VCC1
J 2
(-6660 4810);
DISPLAY 0.489362 (-6660 4810);
FORCEPROP 2 LASTPROP $XRERR UNIQUE?
J 0
(-6900 4810);
DISPLAY 0.638298 (-6900 4810);
PAINT MONO (-6900 4810);
DISPLAY INVISIBLE (-6900 4810);
WIRE 16 -1 (-7125 4800)(-6575 4800);
WIRE 16 -1 (-7125 4800)(-7125 4600);
WIRE 16 -1 (-7125 4600)(-6575 4600);
WIRE 16 -1 (-3675 2050)(-3675 2025);
WIRE 16 -1 (-4575 2050)(-3675 2050);
FORCEPROP 2 LAST SIG_NAME SW_PVDDCR_CPU0_P1_BOOT2_RC
J 2
(-3710 2060);
DISPLAY 0.489362 (-3710 2060);
FORCEPROP 2 LASTPROP $XRERR UNIQUE?
J 0
(-3950 2060);
DISPLAY 0.638298 (-3950 2060);
PAINT MONO (-3950 2060);
DISPLAY INVISIBLE (-3950 2060);
WIRE 16 -1 (-4050 4800)(-4050 4775);
WIRE 16 -1 (-4775 4800)(-4050 4800);
FORCEPROP 2 LAST SIG_NAME SW_PVDDCR_CPU0_P1_BOOT1_RC
J 2
(-4085 4810);
DISPLAY 0.489362 (-4085 4810);
FORCEPROP 2 LASTPROP $XRERR UNIQUE?
J 0
(-4325 4810);
DISPLAY 0.638298 (-4325 4810);
PAINT MONO (-4325 4810);
DISPLAY INVISIBLE (-4325 4810);
WIRE 16 -1 (-7575 2700)(-7575 2825);
WIRE 16 -1 (-7225 2825)(-7575 2825);
WIRE 16 -1 (-7575 2950)(-7575 2825);
WIRE 16 -1 (-6900 2825)(-7225 2825);
WIRE 16 -1 (-7225 2725)(-7225 2825);
WIRE 16 -1 (-6900 2350)(-6900 2825);
WIRE 16 -1 (-6900 2350)(-6550 2350);
WIRE 16 -1 (-5700 1100)(-5550 1100);
WIRE 16 -1 (-5550 1100)(-5550 1150);
WIRE 16 -1 (-5550 1025)(-5550 1100);
WIRE 16 -1 (-5550 1150)(-5550 1200);
WIRE 16 -1 (-5700 1150)(-5550 1150);
WIRE 16 -1 (-5550 1250)(-5550 1200);
WIRE 16 -1 (-5700 1200)(-5550 1200);
WIRE 16 -1 (-5550 1250)(-5700 1250);
WIRE 16 -1 (-5725 3850)(-5550 3850);
WIRE 16 -1 (-5550 3850)(-5550 3900);
WIRE 16 -1 (-5550 3775)(-5550 3850);
WIRE 16 -1 (-5550 3900)(-5550 3950);
WIRE 16 -1 (-5725 3900)(-5550 3900);
WIRE 16 -1 (-5550 4000)(-5550 3950);
WIRE 16 -1 (-5725 3950)(-5550 3950);
WIRE 16 -1 (-5550 4000)(-5725 4000);
WIRE 16 -1 (-8250 5650)(-8250 5575);
WIRE 16 -1 (-8250 5575)(-7900 5575);
WIRE 16 -1 (-7900 5575)(-7600 5575);
WIRE 16 -1 (-7900 5650)(-7900 5575);
WIRE 16 -1 (-7600 5575)(-7425 5575);
WIRE 16 -1 (-7600 5450)(-7600 5575);
WIRE 16 -1 (-7425 5900)(-7425 5575);
WIRE 16 -1 (-7425 5575)(-7250 5575);
WIRE 16 -1 (-6925 5575)(-7250 5575);
WIRE 16 -1 (-7250 5475)(-7250 5575);
WIRE 16 -1 (-6925 5100)(-6925 5575);
WIRE 16 -1 (-6925 5100)(-6575 5100);
WIRE 16 -1 (-1275 1425)(-1275 1300);
WIRE 16 -1 (-1275 1225)(-1275 1300);
WIRE 16 -1 (-1275 1300)(-1700 1300);
WIRE 16 -1 (-1700 1425)(-1700 1300);
WIRE 16 -1 (-1700 1700)(-1900 1700);
WIRE 16 -1 (-1700 1700)(-1275 1700);
WIRE 16 -1 (-1700 1700)(-1700 1625);
WIRE 16 -1 (-1900 1700)(-1900 625);
WIRE 16 -1 (-2475 1700)(-1900 1700);
WIRE 16 -1 (-1900 625)(-4150 625);
WIRE 16 -1 (-1275 1800)(-1275 1700);
WIRE 16 -1 (-1275 1700)(-1275 1625);
WIRE 16 -1 (-1800 2800)(-1800 2650);
WIRE 16 -1 (-1800 2575)(-1800 2650);
WIRE 16 -1 (-1800 2650)(-2100 2650);
WIRE 16 -1 (-2100 2650)(-2100 2800);
WIRE 16 -1 (-2425 2650)(-2100 2650);
WIRE 16 -1 (-2425 2800)(-2425 2650);
WIRE 16 -1 (-2750 2650)(-2425 2650);
WIRE 16 -1 (-2750 2800)(-2750 2650);
WIRE 16 -1 (-3100 2650)(-2750 2650);
WIRE 16 -1 (-3100 2800)(-3100 2650);
WIRE 16 -1 (-1800 3000)(-1800 3100);
WIRE 16 -1 (-1800 3150)(-1800 3100);
WIRE 16 -1 (-1800 3100)(-2100 3100);
WIRE 16 -1 (-2425 3100)(-2100 3100);
WIRE 16 -1 (-2100 3000)(-2100 3100);
WIRE 16 -1 (-2750 3100)(-2425 3100);
WIRE 16 -1 (-2425 3000)(-2425 3100);
WIRE 16 -1 (-2750 3000)(-2750 3100);
WIRE 16 -1 (-3100 3100)(-2750 3100);
WIRE 16 -1 (-3100 3000)(-3100 3100);
WIRE 16 -1 (-925 4175)(-925 4050);
WIRE 16 -1 (-925 3975)(-925 4050);
WIRE 16 -1 (-925 4050)(-1225 4050);
WIRE 16 -1 (-1225 4175)(-1225 4050);
WIRE 16 -1 (-1225 4050)(-1650 4050);
WIRE 16 -1 (-1650 4175)(-1650 4050);
WIRE 16 -1 (-2025 4050)(-1650 4050);
WIRE 16 -1 (-2025 4050)(-2025 4175);
WIRE 16 -1 (-3475 5225)(-3475 5100);
WIRE 16 -1 (-3475 5100)(-3850 5100);
WIRE 16 -1 (-3850 5225)(-3850 5100);
WIRE 16 -1 (-3850 5100)(-4000 5100);
WIRE 16 -1 (-4000 5100)(-4200 5100);
WIRE 16 -1 (-4000 5100)(-4000 5025);
WIRE 16 -1 (-4200 5225)(-4200 5100);
WIRE 16 -1 (-4200 5100)(-4500 5100);
WIRE 16 -1 (-4500 5225)(-4500 5100);
WIRE 16 -1 (-4825 5100)(-4500 5100);
WIRE 16 -1 (-4825 5225)(-4825 5100);
WIRE 16 -1 (-5150 5100)(-4825 5100);
WIRE 16 -1 (-5150 5225)(-5150 5100);
WIRE 16 -1 (-5475 5100)(-5150 5100);
WIRE 16 -1 (-5475 5100)(-5475 5225);
WIRE 16 -1 (-2550 5500)(-2550 5450);
WIRE 16 -1 (-2550 5625)(-2550 5500);
WIRE 16 -1 (-2550 5500)(-2800 5500);
WIRE 16 -1 (-925 4450)(-925 4375);
WIRE 16 -1 (-925 4550)(-925 4450);
WIRE 16 -1 (-925 4450)(-1225 4450);
WIRE 16 -1 (-1225 4450)(-1225 4375);
WIRE 16 -1 (-1225 4450)(-1650 4450);
WIRE 16 -1 (-1650 4450)(-1650 4375);
WIRE 16 -1 (-1650 4450)(-2025 4450);
WIRE 16 -1 (-2025 4375)(-2025 4450);
WIRE 16 -1 (-2150 4450)(-2025 4450);
WIRE 16 -1 (-2925 4450)(-2150 4450);
WIRE 16 -1 (-2150 3475)(-2150 4450);
WIRE 16 -1 (-2150 3475)(-4225 3475);
WIRE 16 -1 (-7200 4150)(-6575 4150);
FORCEPROP 2 LAST SIG_NAME PVDDCR_CPU0_P1_LSET1
J 2
(-6635 4160);
DISPLAY 0.489362 (-6635 4160);
FORCEPROP 2 LASTPROP $XRERR UNIQUE?
J 0
(-6875 4160);
DISPLAY 0.638298 (-6875 4160);
PAINT MONO (-6875 4160);
DISPLAY INVISIBLE (-6875 4160);
WIRE 16 -1 (-5700 1700)(-4650 1700);
FORCEPROP 2 LAST SIG_NAME SW_PVDDCR_CPU0_P1_SW2
J 0
(-5585 1710);
DISPLAY 0.489362 (-5585 1710);
FORCEPROP 2 LASTPROP $XRERR UNIQUE?
J 0
(-5825 1710);
DISPLAY 0.638298 (-5825 1710);
PAINT MONO (-5825 1710);
DISPLAY INVISIBLE (-5825 1710);
WIRE 16 -1 (-4650 1700)(-3275 1700);
WIRE 16 -1 (-4650 1600)(-4650 1700);
WIRE 17 273 (-1350 2325)(-1350 3425);
WIRE 17 273 (-3400 2325)(-1350 2325);
WIRE 17 273 (-1350 3425)(-3400 3425);
WIRE 17 273 (-3400 3425)(-3400 2325);
WIRE 16 -1 (-6575 4450)(-7225 4450);
FORCEPROP 2 LAST SIG_NAME PVDDCR_CPU0_P1_IMON1
J 2
(-6635 4460);
DISPLAY 0.489362 (-6635 4460);
WIRE 16 -1 (-2925 4200)(-2425 4200);
FORCEPROP 2 LAST SIG_NAME IND_CPU0_P1_CPL1
J 0
(-2860 4210);
DISPLAY 0.489362 (-2860 4210);
WIRE 16 -1 (-2150 1450)(-2475 1450);
FORCEPROP 2 LAST SIG_NAME IND_CPU0_P1_CPL2
J 0
(-2485 1460);
DISPLAY 0.489362 (-2485 1460);
WIRE 16 -1 (-3725 1450)(-3275 1450);
FORCEPROP 2 LAST SIG_NAME IND_CPU0_P1_CPL1
J 0
(-3710 1460);
DISPLAY 0.489362 (-3710 1460);
WIRE 16 -1 (-4200 4200)(-3725 4200);
FORCEPROP 2 LAST SIG_NAME IND_CPU0_P1_CPL5
J 0
(-4160 4210);
DISPLAY 0.489362 (-4160 4210);
WIRE 16 -1 (-5725 4150)(-5200 4150);
FORCEPROP 2 LAST SIG_NAME NC_PVDDCR_CPU0_P1_GL1_1
J 0
(-5610 4160);
DISPLAY 0.489362 (-5610 4160);
FORCEPROP 2 LASTPROP $XRERR UNIQUE?
J 0
(-5170 4150);
DISPLAY 0.638298 (-5170 4150);
PAINT MONO (-5170 4150);
DISPLAY INVISIBLE (-5170 4150);
WIRE 16 -1 (-5725 4100)(-5200 4100);
FORCEPROP 2 LAST SIG_NAME NC_PVDDCR_CPU0_P1_GL2_1
J 0
(-5610 4110);
DISPLAY 0.489362 (-5610 4110);
FORCEPROP 2 LASTPROP $XRERR UNIQUE?
J 0
(-5170 4100);
DISPLAY 0.638298 (-5170 4100);
PAINT MONO (-5170 4100);
DISPLAY INVISIBLE (-5170 4100);
WIRE 16 -1 (-6575 4200)(-7025 4200);
FORCEPROP 2 LAST SIG_NAME NC_PVDDCR_CPU0_P1_DNC1
J 2
(-6635 4210);
DISPLAY 0.489362 (-6635 4210);
FORCEPROP 2 LASTPROP $XRERR UNIQUE?
J 0
(-7265 4200);
DISPLAY 0.638298 (-7265 4200);
PAINT MONO (-7265 4200);
DISPLAY INVISIBLE (-7265 4200);
WIRE 16 -1 (-8125 4350)(-7950 4350);
WIRE 16 -1 (-6575 4350)(-7950 4350);
FORCEPROP 2 LAST SIG_NAME PVDDCR_CPU0_P1_VCCS
J 2
(-6635 4360);
DISPLAY 0.489362 (-6635 4360);
WIRE 16 -1 (-7950 4275)(-7950 4350);
WIRE 16 -1 (-4800 4150)(-4800 3875);
FORCEPROP 2 LAST SIG_NAME SW_PVDDCR_CPU0_P1_SW1_RC
J 0
(-4760 3985);
DISPLAY 0.489362 (-4760 3985);
FORCEPROP 2 LASTPROP $XRERR UNIQUE?
J 0
(-5000 3985);
DISPLAY 0.638298 (-5000 3985);
PAINT MONO (-5000 3985);
DISPLAY INVISIBLE (-5000 3985);
WIRE 16 -1 (-4650 1400)(-4650 1100);
FORCEPROP 2 LAST SIG_NAME SW_PVDDCR_CPU0_P1_SW2_RC
J 0
(-4610 1210);
DISPLAY 0.489362 (-4610 1210);
FORCEPROP 2 LASTPROP $XRERR UNIQUE?
J 0
(-4850 1210);
DISPLAY 0.638298 (-4850 1210);
PAINT MONO (-4850 1210);
DISPLAY INVISIBLE (-4850 1210);
WIRE 16 -1 (-4350 625)(-4950 625);
FORCEPROP 2 LAST SIG_NAME PVDDCR_CPU0_P1_VOS2
J 0
(-5585 1475);
DISPLAY 0.489362 (-5585 1475);
FORCEPROP 2 LASTPROP $XRERR UNIQUE?
J 0
(-5825 1475);
DISPLAY 0.638298 (-5825 1475);
PAINT MONO (-5825 1475);
DISPLAY INVISIBLE (-5825 1475);
WIRE 16 -1 (-4950 625)(-4950 1450);
WIRE 16 -1 (-5700 1450)(-4950 1450);
WIRE 16 -1 (-5700 1350)(-5175 1350);
FORCEPROP 2 LAST SIG_NAME NC_PVDDCR_CPU0_P1_GL2_2
J 0
(-5585 1360);
DISPLAY 0.489362 (-5585 1360);
FORCEPROP 2 LASTPROP $XRERR UNIQUE?
J 0
(-5145 1350);
DISPLAY 0.638298 (-5145 1350);
PAINT MONO (-5145 1350);
DISPLAY INVISIBLE (-5145 1350);
WIRE 16 -1 (-5700 1400)(-5175 1400);
FORCEPROP 2 LAST SIG_NAME NC_PVDDCR_CPU0_P1_GL1_2
J 0
(-5585 1410);
DISPLAY 0.489362 (-5585 1410);
FORCEPROP 2 LASTPROP $XRERR UNIQUE?
J 0
(-5145 1400);
DISPLAY 0.638298 (-5145 1400);
PAINT MONO (-5145 1400);
DISPLAY INVISIBLE (-5145 1400);
WIRE 16 -1 (-6575 3850)(-7175 3850);
FORCEPROP 2 LAST SIG_NAME PVDDCR_CPU0_P1_PWM1
J 2
(-6635 3860);
DISPLAY 0.489362 (-6635 3860);
WIRE 16 -1 (-6575 3950)(-7200 3950);
FORCEPROP 2 LAST SIG_NAME PVDDCR_CPU0_P1_TEMP0
J 2
(-6635 3960);
DISPLAY 0.489362 (-6635 3960);
WIRE 16 -1 (-6550 1450)(-7000 1450);
FORCEPROP 2 LAST SIG_NAME NC_PVDDCR_CPU0_P1_DNC2
J 2
(-6610 1460);
DISPLAY 0.489362 (-6610 1460);
FORCEPROP 2 LASTPROP $XRERR UNIQUE?
J 0
(-7240 1450);
DISPLAY 0.638298 (-7240 1450);
PAINT MONO (-7240 1450);
DISPLAY INVISIBLE (-7240 1450);
WIRE 16 -1 (-7175 1400)(-6550 1400);
FORCEPROP 2 LAST SIG_NAME PVDDCR_CPU0_P1_LSET2
J 2
(-6610 1410);
DISPLAY 0.489362 (-6610 1410);
FORCEPROP 2 LASTPROP $XRERR UNIQUE?
J 0
(-6850 1410);
DISPLAY 0.638298 (-6850 1410);
PAINT MONO (-6850 1410);
DISPLAY INVISIBLE (-6850 1410);
WIRE 16 -1 (-6550 1700)(-7200 1700);
FORCEPROP 2 LAST SIG_NAME PVDDCR_CPU0_P1_IMON2
J 2
(-6610 1710);
DISPLAY 0.489362 (-6610 1710);
WIRE 16 -1 (-6550 1200)(-7175 1200);
FORCEPROP 2 LAST SIG_NAME PVDDCR_CPU0_P1_TEMP0
J 2
(-6610 1210);
DISPLAY 0.489362 (-6610 1210);
WIRE 16 -1 (-6550 1100)(-7150 1100);
FORCEPROP 2 LAST SIG_NAME PVDDCR_CPU0_P1_PWM2
J 2
(-6610 1110);
DISPLAY 0.489362 (-6610 1110);
DOT 1 (-5475 2750);
DOT 1 (-925 4450);
DOT 1 (-1225 4450);
DOT 1 (-1650 4450);
DOT 1 (-2550 5500);
DOT 1 (-2025 4450);
DOT 1 (-2150 4450);
DOT 1 (-3475 5500);
DOT 1 (-4025 5500);
DOT 1 (-4000 5100);
DOT 1 (-925 4050);
DOT 1 (-1225 4050);
DOT 1 (-1650 4050);
DOT 1 (-1800 3100);
DOT 1 (-1800 2650);
DOT 1 (-1275 1700);
DOT 1 (-1275 1300);
DOT 1 (-1700 1700);
DOT 1 (-1900 1700);
DOT 1 (-2100 3100);
DOT 1 (-2425 3100);
DOT 1 (-2750 3100);
DOT 1 (-2100 2650);
DOT 1 (-2425 2650);
DOT 1 (-2750 2650);
DOT 1 (-4200 5500);
DOT 1 (-4500 5500);
DOT 1 (-4825 5500);
DOT 1 (-4200 5100);
DOT 1 (-4500 5100);
DOT 1 (-4800 4450);
DOT 1 (-5150 5500);
DOT 1 (-5475 5500);
DOT 1 (-5150 5100);
DOT 1 (-5625 5100);
DOT 1 (-7250 5575);
DOT 1 (-7425 5575);
DOT 1 (-7600 5575);
DOT 1 (-7900 5575);
DOT 1 (-7125 4800);
DOT 1 (-7600 4975);
DOT 1 (-7950 4350);
DOT 1 (-4200 2750);
DOT 1 (-4500 2750);
DOT 1 (-4200 2350);
DOT 1 (-4500 2350);
DOT 1 (-4825 2750);
DOT 1 (-4825 2350);
DOT 1 (-5550 3950);
DOT 1 (-5550 3900);
DOT 1 (-5550 3850);
DOT 1 (-5150 2750);
DOT 1 (-5150 2350);
DOT 1 (-5600 2350);
DOT 1 (-4650 1700);
DOT 1 (-5550 1200);
DOT 1 (-5550 1150);
DOT 1 (-5550 1100);
DOT 1 (-7225 2825);
DOT 1 (-7575 2825);
DOT 1 (-7575 2225);
DOT 1 (-7100 2050);
DOT 1 (-7925 1600);
DOT 1 (-3850 5500);
DOT 1 (-3850 5100);
DOT 1 (-4825 5100);
FORCENOTE
MAIN SOURCE:RENESAS BOM
(-9700 900) 0;
DISPLAY LEFT (-9700 900);
DISPLAY 1.276596 (-9700 900);
PAINT WHITE (-9700 900);
FORCENOTE
PU4,PU26,PU27,PU28,PU29,PU24 = AL099390004/ISL99390FRZ-TR5935
(-9700 825) 0;
DISPLAY LEFT (-9700 825);
DISPLAY 1.021277 (-9700 825);
PAINT WHITE (-9700 825);
FORCENOTE
PU4,PU26,PU27,PU28,PU29,PU24 = AL021590000/TDA21590
(-9700 600) 0;
DISPLAY LEFT (-9700 600);
DISPLAY 1.021277 (-9700 600);
PAINT WHITE (-9700 600);
FORCENOTE
PR189,PR190,PR197,PR198,PR203,PR424 = CS00002JB13
(-9700 525) 0;
DISPLAY LEFT (-9700 525);
DISPLAY 1.021277 (-9700 525);
PAINT WHITE (-9700 525);
FORCENOTE
PR187,PR188,PR195,PR196,PR202,PR423 = CS00002JB13
(-9700 450) 0;
DISPLAY LEFT (-9700 450);
DISPLAY 1.021277 (-9700 450);
PAINT WHITE (-9700 450);
FORCENOTE
2ND SOURCE:INFENEON BOM
(-9700 675) 0;
DISPLAY LEFT (-9700 675);
DISPLAY 1.276596 (-9700 675);
PAINT WHITE (-9700 675);
FORCENOTE
PU4,PU26,PU27,PU28,PU29,PU24 = AL087000A03/MP87000GMJTH-C11D-Z
(-9725 50) 0;
DISPLAY LEFT (-9725 50);
DISPLAY 1.021277 (-9725 50);
PAINT WHITE (-9725 50);
FORCENOTE
PR336,PR189,PR190,PR197,PR198,PR203,PR424=CS00002JB13
(-9725 -25) 0;
DISPLAY LEFT (-9725 -25);
DISPLAY 1.021277 (-9725 -25);
PAINT WHITE (-9725 -25);
FORCENOTE
3RD SOURCE:MPS BOM
(-9725 125) 0;
DISPLAY LEFT (-9725 125);
DISPLAY 1.276596 (-9725 125);
PAINT WHITE (-9725 125);
FORCENOTE
PC254_1,PC255_2,PC284_3,PC285_4,PC306_5,PC124_6 = EMPTY
(-9700 300) 0;
DISPLAY LEFT (-9700 300);
DISPLAY 1.021277 (-9700 300);
PAINT WHITE (-9700 300);
FORCENOTE
PR191,PR192,PR199,PR200,PR204,PR425 = EMPTY
(-9700 375) 0;
DISPLAY LEFT (-9700 375);
DISPLAY 1.021277 (-9700 375);
PAINT WHITE (-9700 375);
FORCENOTE
PC254_1,PC255_2,PC284_3,PC285_4,PC306_5,PC124_6=EMPTY
(-9725 -175) 0;
DISPLAY LEFT (-9725 -175);
DISPLAY 1.021277 (-9725 -175);
PAINT WHITE (-9725 -175);
FORCENOTE
PR335,PR191,PR192,PR199,PR200,PR204,PR425=EMPTY
(-9725 -100) 0;
DISPLAY LEFT (-9725 -100);
DISPLAY 1.021277 (-9725 -100);
PAINT WHITE (-9725 -100);
FORCENOTE
PVDDCR_CPU0_P1_PHASE2
(-6675 3025) 0;
DISPLAY LEFT (-6675 3025);
DISPLAY 1.595745 (-6675 3025);
PAINT WHITE (-6675 3025);
FORCENOTE
PVDDCR_CPU0_P1_PHASE1
(-6700 5850) 0;
DISPLAY LEFT (-6700 5850);
DISPLAY 1.595745 (-6700 5850);
PAINT WHITE (-6700 5850);
FORCENOTE
PG2292.500HLT
(-3100 5425) 0;
DISPLAY LEFT (-3100 5425);
DISPLAY 0.638298 (-3100 5425);
PAINT WHITE (-3100 5425);
FORCENOTE
DCR=0.09M OHM
(-3100 5275) 0;
DISPLAY LEFT (-3100 5275);
DISPLAY 0.638298 (-3100 5275);
PAINT WHITE (-3100 5275);
FORCENOTE
2ND=CVA50^0MZ07
(-3100 5225) 0;
DISPLAY LEFT (-3100 5225);
DISPLAY 0.638298 (-3100 5225);
PAINT WHITE (-3100 5225);
FORCENOTE
3RD=CVA50^0MZ08
(-3100 5175) 0;
DISPLAY LEFT (-3100 5175);
DISPLAY 0.638298 (-3100 5175);
PAINT WHITE (-3100 5175);
FORCENOTE
2ND=CV+15^0TZ01
(-2925 4525) 0;
DISPLAY LEFT (-2925 4525);
DISPLAY 0.638298 (-2925 4525);
PAINT WHITE (-2925 4525);
FORCENOTE
11.0*7.5*12.5
(-2925 4675) 0;
DISPLAY LEFT (-2925 4675);
DISPLAY 0.638298 (-2925 4675);
PAINT WHITE (-2925 4675);
FORCENOTE
6.3*8
(-3750 4950) 0;
DISPLAY LEFT (-3750 4950);
DISPLAY 0.638298 (-3750 4950);
PAINT WHITE (-3750 4950);
FORCENOTE
DCR=1-4,0.105M OHM
(-2475 1875) 0;
DISPLAY LEFT (-2475 1875);
DISPLAY 0.638298 (-2475 1875);
PAINT WHITE (-2475 1875);
FORCENOTE
DCR=2-3,0.27M OHM
(-2475 1825) 0;
DISPLAY LEFT (-2475 1825);
DISPLAY 0.638298 (-2475 1825);
PAINT WHITE (-2475 1825);
FORCENOTE
ESR=9M OHM
(-2450 2550) 0;
DISPLAY LEFT (-2450 2550);
DISPLAY 0.638298 (-2450 2550);
PAINT WHITE (-2450 2550);
FORCENOTE
7.3*4.3*1.9
(-2450 2500) 0;
DISPLAY LEFT (-2450 2500);
DISPLAY 0.638298 (-2450 2500);
PAINT WHITE (-2450 2500);
FORCENOTE
MAIN=CH122KM8801
(-2500 2450) 0;
DISPLAY LEFT (-2500 2450);
DISPLAY 0.638298 (-2500 2450);
PAINT WHITE (-2500 2450);
FORCENOTE
PGL6303.151HLT
(-2475 2025) 0;
DISPLAY LEFT (-2475 2025);
DISPLAY 0.638298 (-2475 2025);
PAINT WHITE (-2475 2025);
FORCENOTE
11.0*7.5*12.5
(-2475 1925) 0;
DISPLAY LEFT (-2475 1925);
DISPLAY 0.638298 (-2475 1925);
PAINT WHITE (-2475 1925);
FORCENOTE
2ND=CV+15^0TZ01
(-2475 1775) 0;
DISPLAY LEFT (-2475 1775);
DISPLAY 0.638298 (-2475 1775);
PAINT WHITE (-2475 1775);
FORCENOTE
ISAT:70A@100C
(-2475 1975) 0;
DISPLAY LEFT (-2475 1975);
DISPLAY 0.638298 (-2475 1975);
PAINT WHITE (-2475 1975);
FORCENOTE
ISAT:70A@100C
(-3100 5375) 0;
DISPLAY LEFT (-3100 5375);
DISPLAY 0.638298 (-3100 5375);
PAINT WHITE (-3100 5375);
FORCENOTE
6.0*6.1*7.0
(-3100 5325) 0;
DISPLAY LEFT (-3100 5325);
DISPLAY 0.638298 (-3100 5325);
PAINT WHITE (-3100 5325);
FORCENOTE
DCR=2-3,0.27M OHM
(-2925 4575) 0;
DISPLAY LEFT (-2925 4575);
DISPLAY 0.638298 (-2925 4575);
PAINT WHITE (-2925 4575);
FORCENOTE
DCR=1-4,0.105M OHM
(-2925 4625) 0;
DISPLAY LEFT (-2925 4625);
DISPLAY 0.638298 (-2925 4625);
PAINT WHITE (-2925 4625);
FORCENOTE
ISAT:70A@100C
(-2925 4725) 0;
DISPLAY LEFT (-2925 4725);
DISPLAY 0.638298 (-2925 4725);
PAINT WHITE (-2925 4725);
FORCENOTE
PGL6303.151HLT
(-2925 4775) 0;
DISPLAY LEFT (-2925 4775);
DISPLAY 0.638298 (-2925 4775);
PAINT WHITE (-2925 4775);
FORCENOTE
2ND=CC72703MD39
(-3750 4900) 0;
DISPLAY LEFT (-3750 4900);
DISPLAY 0.638298 (-3750 4900);
PAINT WHITE (-3750 4900);
FORCENOTE
IRIPPLE:5.08A
(-3750 5000) 0;
DISPLAY LEFT (-3750 5000);
DISPLAY 0.638298 (-3750 5000);
PAINT WHITE (-3750 5000);
FORCENOTE
ESR=10M OHM
(-3750 5050) 0;
DISPLAY LEFT (-3750 5050);
DISPLAY 0.638298 (-3750 5050);
PAINT WHITE (-3750 5050);
FORCENOTE
BOM NOTE
(-9700 1025) 0;
DISPLAY LEFT (-9700 1025);
DISPLAY 1.595745 (-9700 1025);
PAINT WHITE (-9700 1025);
QUIT
